FILE_TYPE = MACRO_DRAWING;
SET COLOR_WIRE YELLOW;
SET COLOR_PROP ORANGE;
SET COLOR_DOT WHITE;
SET COLOR_ARC YELLOW;
SET COLOR_BODY GREEN;
SET COLOR_NOTE PURPLE;
SET PROP_DISPLAY VALUE;
SET PAGE_NUMBER P14;
FORCEADD SOCKET4677_AZIF0045P001C01CS..2
(-350 3250);
FORCEPROP 1 LAST PART_NUMBER DGA^7000023
J 0
(-1450 4750);
DISPLAY 0.723404 (-1450 4750);
PAINT GREEN (-1450 4750);
DISPLAY INVISIBLE (-1450 4750);
FORCEPROP 2 LAST VALUE SOCKET4677_AZIF0045-P001C01CS
J 0
(-1450 4875);
DISPLAY 1.021277 (-1450 4875);
FORCEPROP 1 LAST MATERIAL IO
J 0
(-1450 4675);
DISPLAY 0.723404 (-1450 4675);
PAINT GREEN (-1450 4675);
FORCEPROP 2 LAST PART_TYPE SMLF
J 0
(-1450 4925);
DISPLAY 1.021277 (-1450 4925);
FORCEPROP 1 LAST $LOCATION U2
J 0
(-1450 4825);
DISPLAY 0.723404 (-1450 4825);
PAINT GREEN (-1450 4825);
FORCEPROP 0 LASTPIN (875 3900) $PN BP24
J 0
(885 3910);
DISPLAY 0.680851 (885 3910);
PAINT MONO (885 3910);
FORCEPROP 0 LASTPIN (-1575 3850) $PN BV26
J 2
(-1585 3860);
DISPLAY 0.680851 (-1585 3860);
PAINT MONO (-1585 3860);
FORCEPROP 0 LASTPIN (-1575 3950) $PN CA25
J 2
(-1585 3960);
DISPLAY 0.680851 (-1585 3960);
PAINT MONO (-1585 3960);
FORCEPROP 0 LASTPIN (-1575 3900) $PN BY26
J 2
(-1585 3910);
DISPLAY 0.680851 (-1585 3910);
PAINT MONO (-1585 3910);
FORCEPROP 0 LASTPIN (-1575 2300) $PN A43
J 2
(-1585 2310);
DISPLAY 0.680851 (-1585 2310);
PAINT MONO (-1585 2310);
FORCEPROP 0 LASTPIN (-1575 2250) $PN F47
J 2
(-1585 2260);
DISPLAY 0.680851 (-1585 2260);
PAINT MONO (-1585 2260);
FORCEPROP 0 LASTPIN (-1575 2200) $PN CY44
J 2
(-1585 2210);
DISPLAY 0.680851 (-1585 2210);
PAINT MONO (-1585 2210);
FORCEPROP 0 LASTPIN (-1575 2150) $PN CW45
J 2
(-1585 2160);
DISPLAY 0.680851 (-1585 2160);
PAINT MONO (-1585 2160);
FORCEPROP 0 LASTPIN (875 3450) $PN AV57
J 0
(885 3460);
DISPLAY 0.680851 (885 3460);
PAINT MONO (885 3460);
FORCEPROP 0 LASTPIN (875 3800) $PN AU21
J 0
(885 3810);
DISPLAY 0.680851 (885 3810);
PAINT MONO (885 3810);
FORCEPROP 0 LASTPIN (875 3750) $PN CF26
J 0
(885 3760);
DISPLAY 0.680851 (885 3760);
PAINT MONO (885 3760);
FORCEPROP 0 LASTPIN (875 3700) $PN AV24
J 0
(885 3710);
DISPLAY 0.680851 (885 3710);
PAINT MONO (885 3710);
FORCEPROP 0 LASTPIN (875 3600) $PN AV18
J 0
(885 3610);
DISPLAY 0.680851 (885 3610);
PAINT MONO (885 3610);
FORCEPROP 0 LASTPIN (-1575 3150) $PN CW39
J 2
(-1585 3160);
DISPLAY 0.680851 (-1585 3160);
PAINT MONO (-1585 3160);
FORCEPROP 0 LASTPIN (-1575 3050) $PN CP26
J 2
(-1585 3060);
DISPLAY 0.680851 (-1585 3060);
PAINT MONO (-1585 3060);
FORCEPROP 0 LASTPIN (-1575 2950) $PN CM26
J 2
(-1585 2960);
DISPLAY 0.680851 (-1585 2960);
PAINT MONO (-1585 2960);
FORCEPROP 0 LASTPIN (-1575 2850) $PN CD24
J 2
(-1585 2860);
DISPLAY 0.680851 (-1585 2860);
PAINT MONO (-1585 2860);
FORCEPROP 0 LASTPIN (-1575 2750) $PN CV18
J 2
(-1585 2760);
DISPLAY 0.680851 (-1585 2760);
PAINT MONO (-1585 2760);
FORCEPROP 0 LASTPIN (-1575 2650) $PN CE23
J 2
(-1585 2660);
DISPLAY 0.680851 (-1585 2660);
PAINT MONO (-1585 2660);
FORCEPROP 0 LASTPIN (-1575 2550) $PN CC25
J 2
(-1585 2560);
DISPLAY 0.680851 (-1585 2560);
PAINT MONO (-1585 2560);
FORCEPROP 0 LASTPIN (-1575 3250) $PN CY40
J 2
(-1585 3260);
DISPLAY 0.680851 (-1585 3260);
PAINT MONO (-1585 3260);
FORCEPROP 0 LASTPIN (875 3350) $PN CP20
J 0
(885 3360);
DISPLAY 0.680851 (885 3360);
PAINT MONO (885 3360);
FORCEPROP 0 LASTPIN (-1575 3200) $PN CN25
J 2
(-1585 3210);
DISPLAY 0.680851 (-1585 3210);
PAINT MONO (-1585 3210);
FORCEPROP 0 LASTPIN (-1575 3100) $PN CL25
J 2
(-1585 3110);
DISPLAY 0.680851 (-1585 3110);
PAINT MONO (-1585 3110);
FORCEPROP 0 LASTPIN (-1575 3000) $PN CH26
J 2
(-1585 3010);
DISPLAY 0.680851 (-1585 3010);
PAINT MONO (-1585 3010);
FORCEPROP 0 LASTPIN (-1575 2900) $PN CE25
J 2
(-1585 2910);
DISPLAY 0.680851 (-1585 2910);
PAINT MONO (-1585 2910);
FORCEPROP 0 LASTPIN (-1575 2800) $PN CR19
J 2
(-1585 2810);
DISPLAY 0.680851 (-1585 2810);
PAINT MONO (-1585 2810);
FORCEPROP 0 LASTPIN (-1575 2700) $PN CH24
J 2
(-1585 2710);
DISPLAY 0.680851 (-1585 2710);
PAINT MONO (-1585 2710);
FORCEPROP 0 LASTPIN (-1575 2600) $PN CF24
J 2
(-1585 2610);
DISPLAY 0.680851 (-1585 2610);
PAINT MONO (-1585 2610);
FORCEPROP 0 LASTPIN (-1575 3300) $PN DA39
J 2
(-1585 3310);
DISPLAY 0.680851 (-1585 3310);
PAINT MONO (-1585 3310);
FORCEPROP 0 LASTPIN (875 3850) $PN AU19
J 0
(885 3860);
DISPLAY 0.680851 (885 3860);
PAINT MONO (885 3860);
FORCEPROP 0 LASTPIN (-1575 2000) $PN BH61
J 2
(-1585 2010);
DISPLAY 0.680851 (-1585 2010);
PAINT MONO (-1585 2010);
FORCEPROP 0 LASTPIN (-1575 3650) $PN CG66
J 2
(-1585 3660);
DISPLAY 0.680851 (-1585 3660);
PAINT MONO (-1585 3660);
FORCEPROP 0 LASTPIN (875 4400) $PN BK26
J 0
(885 4410);
DISPLAY 0.680851 (885 4410);
PAINT MONO (885 4410);
FORCEPROP 0 LASTPIN (875 4200) $PN BJ25
J 0
(885 4210);
DISPLAY 0.680851 (885 4210);
PAINT MONO (885 4210);
FORCEPROP 0 LASTPIN (875 4450) $PN BH26
J 0
(885 4460);
DISPLAY 0.680851 (885 4460);
PAINT MONO (885 4460);
FORCEPROP 0 LASTPIN (875 4250) $PN BF26
J 0
(885 4260);
DISPLAY 0.680851 (885 4260);
PAINT MONO (885 4260);
FORCEPROP 0 LASTPIN (875 4500) $PN BD26
J 0
(885 4510);
DISPLAY 0.680851 (885 4510);
PAINT MONO (885 4510);
FORCEPROP 0 LASTPIN (875 4300) $PN BL25
J 0
(885 4310);
DISPLAY 0.680851 (885 4310);
PAINT MONO (885 4310);
FORCEPROP 0 LASTPIN (-1575 3600) $PN AY20
J 2
(-1585 3610);
DISPLAY 0.680851 (-1585 3610);
PAINT MONO (-1585 3610);
FORCEPROP 0 LASTPIN (875 3650) $PN BL62
J 0
(885 3660);
DISPLAY 0.680851 (885 3660);
PAINT MONO (885 3660);
FORCEPROP 0 LASTPIN (875 4100) $PN BF22
J 0
(885 4110);
DISPLAY 0.680851 (885 4110);
PAINT MONO (885 4110);
FORCEPROP 0 LASTPIN (875 4050) $PN AY22
J 0
(885 4060);
DISPLAY 0.680851 (885 4060);
PAINT MONO (885 4060);
FORCEPROP 0 LASTPIN (875 4000) $PN BD22
J 0
(885 4010);
DISPLAY 0.680851 (885 4010);
PAINT MONO (885 4010);
FORCEPROP 0 LASTPIN (-1575 4150) $PN CR70
J 2
(-1585 4160);
DISPLAY 0.680851 (-1585 4160);
PAINT MONO (-1585 4160);
FORCEPROP 0 LASTPIN (-1575 4100) $PN CT71
J 2
(-1585 4110);
DISPLAY 0.680851 (-1585 4110);
PAINT MONO (-1585 4110);
FORCEPROP 0 LASTPIN (-1575 4050) $PN CP71
J 2
(-1585 4060);
DISPLAY 0.680851 (-1585 4060);
PAINT MONO (-1585 4060);
FORCEPROP 0 LASTPIN (-1575 4300) $PN CU70
J 2
(-1585 4310);
DISPLAY 0.680851 (-1585 4310);
PAINT MONO (-1585 4310);
FORCEPROP 0 LASTPIN (-1575 4250) $PN CM71
J 2
(-1585 4260);
DISPLAY 0.680851 (-1585 4260);
PAINT MONO (-1585 4260);
FORCEPROP 0 LASTPIN (-1575 4200) $PN CR72
J 2
(-1585 4210);
DISPLAY 0.680851 (-1585 4210);
PAINT MONO (-1585 4210);
FORCEPROP 0 LASTPIN (-1575 2100) $PN AV20
J 2
(-1585 2110);
DISPLAY 0.680851 (-1585 2110);
PAINT MONO (-1585 2110);
FORCEPROP 0 LASTPIN (875 3000) $PN AT24
J 0
(885 3010);
DISPLAY 0.680851 (885 3010);
PAINT MONO (885 3010);
FORCEPROP 0 LASTPIN (875 2950) $PN AU25
J 0
(885 2960);
DISPLAY 0.680851 (885 2960);
PAINT MONO (885 2960);
FORCEPROP 0 LASTPIN (875 2900) $PN AV26
J 0
(885 2910);
DISPLAY 0.680851 (885 2910);
PAINT MONO (885 2910);
FORCEPROP 0 LASTPIN (875 3400) $PN AV59
J 0
(885 3410);
DISPLAY 0.680851 (885 3410);
PAINT MONO (885 3410);
FORCEPROP 0 LASTPIN (875 3050) $PN AY26
J 0
(885 3060);
DISPLAY 0.680851 (885 3060);
PAINT MONO (885 3060);
FORCEPROP 0 LASTPIN (875 2700) $PN AY65
J 0
(885 2710);
DISPLAY 0.680851 (885 2710);
PAINT MONO (885 2710);
FORCEPROP 0 LASTPIN (875 2650) $PN BJ70
J 0
(885 2660);
DISPLAY 0.680851 (885 2660);
PAINT MONO (885 2660);
FORCEPROP 0 LASTPIN (875 2750) $PN BP67
J 0
(885 2760);
DISPLAY 0.680851 (885 2760);
PAINT MONO (885 2760);
FORCEPROP 0 LASTPIN (875 2800) $PN BP69
J 0
(885 2810);
DISPLAY 0.680851 (885 2810);
PAINT MONO (885 2810);
FORCEPROP 0 LASTPIN (-1575 3750) $PN CH22
J 2
(-1585 3760);
DISPLAY 0.680851 (-1585 3760);
PAINT MONO (-1585 3760);
FORCEPROP 0 LASTPIN (875 2300) $PN CJ62
J 0
(885 2310);
DISPLAY 0.680851 (885 2310);
PAINT MONO (885 2310);
FORCEPROP 0 LASTPIN (-1575 3350) $PN CL21
J 2
(-1585 3360);
DISPLAY 0.680851 (-1585 3360);
PAINT MONO (-1585 3360);
FORCEPROP 0 LASTPIN (875 2150) $PN CL64
J 0
(885 2160);
DISPLAY 0.680851 (885 2160);
PAINT MONO (885 2160);
FORCEPROP 0 LASTPIN (875 2200) $PN CM63
J 0
(885 2210);
DISPLAY 0.680851 (885 2210);
PAINT MONO (885 2210);
FORCEPROP 0 LASTPIN (875 2250) $PN CN62
J 0
(885 2260);
DISPLAY 0.680851 (885 2260);
PAINT MONO (885 2260);
FORCEPROP 0 LASTPIN (875 2550) $PN CR23
J 0
(885 2560);
DISPLAY 0.680851 (885 2560);
PAINT MONO (885 2560);
FORCEPROP 0 LASTPIN (875 2450) $PN CV24
J 0
(885 2460);
DISPLAY 0.680851 (885 2460);
PAINT MONO (885 2460);
FORCEPROP 0 LASTPIN (875 2400) $PN CW23
J 0
(885 2410);
DISPLAY 0.680851 (885 2410);
PAINT MONO (885 2410);
FORCEPROP 0 LASTPIN (875 2500) $PN CW25
J 0
(885 2510);
DISPLAY 0.680851 (885 2510);
PAINT MONO (885 2510);
FORCEPROP 0 LASTPIN (875 3200) $PN CW68
J 0
(885 3210);
DISPLAY 0.680851 (885 3210);
PAINT MONO (885 3210);
FORCEPROP 1 LAST CDS_LMAN_SYM_OUTLINE -1100,1400,1050,-1400
J 0
(-350 3250);
DISPLAY 0.468085 (-350 3250);
PAINT GREEN (-350 3250);
DISPLAY INVISIBLE (-350 3250);
FORCEPROP 1 LAST NEEDS_NO_SIZE TRUE
J 0
(-350 3250);
DISPLAY 0.723404 (-350 3250);
PAINT GREEN (-350 3250);
DISPLAY INVISIBLE (-350 3250);
FORCEPROP 2 LAST CDS_LIB pure_quanta
J 0
(-350 3250);
DISPLAY INVISIBLE (-350 3250);
FORCEPROP 2 LAST CDS_LOCATION U2
J 0
(-1450 4975);
DISPLAY 1.021277 (-1450 4975);
DISPLAY INVISIBLE (-1450 4975);
FORCEPROP 0 LAST $SEC 2
J 0
(-1450 4975);
DISPLAY 0.680851 (-1450 4975);
PAINT MONO (-1450 4975);
DISPLAY INVISIBLE (-1450 4975);
FORCEPROP 2 LAST CDS_SEC 2
J 0
(-1450 4975);
DISPLAY 1.021277 (-1450 4975);
DISPLAY INVISIBLE (-1450 4975);
FORCEPROP 1 LAST PATH I1
J 0
(-350 3250);
DISPLAY 0.723404 (-350 3250);
PAINT GREEN (-350 3250);
DISPLAY INVISIBLE (-350 3250);
FORCEADD Q_RES..1
(2975 -225);
FORCEPROP 1 LAST PART_NUMBER CS04992FB07
J 0
(2825 -175);
DISPLAY 0.638298 (2825 -175);
DISPLAY INVISIBLE (2825 -175);
FORCEPROP 1 LAST TOLERANCE 1%
J 0
(3225 -225);
DISPLAY 0.638298 (3225 -225);
FORCEPROP 1 LAST VALUE 49.9
J 2
(3350 -225);
DISPLAY 0.638298 (3350 -225);
FORCEPROP 1 LAST MATERIAL CHIP
J 0
(3300 -225);
DISPLAY 0.638298 (3300 -225);
FORCEPROP 1 LAST WATTAGE 1/16W
J 2
(3175 -125);
DISPLAY 0.638298 (3175 -125);
FORCEPROP 1 LAST PACK_TYPE 0402LF
J 0
(2825 -125);
DISPLAY 0.638298 (2825 -125);
FORCEPROP 1 LAST $LOCATION R556
J 0
(2725 -225);
DISPLAY 0.808511 (2725 -225);
FORCEPROP 1 LASTPIN (2875 -225) $PN 1
J 0
(2887 -213);
DISPLAY 0.787234 (2887 -213);
FORCEPROP 1 LASTPIN (3075 -225) $PN 2
J 0
(3037 -213);
DISPLAY 0.787234 (3037 -213);
FORCEPROP 2 LAST CDS_LIB pure_quanta
J 0
(2975 -225);
PAINT MONO (2975 -225);
DISPLAY INVISIBLE (2975 -225);
FORCEPROP 2 LAST CDS_LOCATION R556
J 0
(2925 -25);
DISPLAY 1.021277 (2925 -25);
DISPLAY INVISIBLE (2925 -25);
FORCEPROP 2 LAST $SEC 1
J 0
(2925 -25);
DISPLAY 0.680851 (2925 -25);
PAINT MONO (2925 -25);
DISPLAY INVISIBLE (2925 -25);
FORCEPROP 2 LAST CDS_SEC 1
J 0
(2925 -25);
DISPLAY 1.021277 (2925 -25);
DISPLAY INVISIBLE (2925 -25);
FORCEPROP 1 LAST PATH I100
J 0
(2925 -75);
DISPLAY 0.978723 (2925 -75);
PAINT WHITE (2925 -75);
DISPLAY INVISIBLE (2925 -75);
FORCEADD OFFPAGE..2
R 2
(1650 -225);
FORCEPROP 2 LAST $XR1 14 
J 0
(1305 -225);
DISPLAY 0.638298 (1305 -225);
PAINT MONO (1305 -225);
FORCEPROP 2 LAST $XR0 278 
J 0
(1395 -225);
DISPLAY 0.638298 (1395 -225);
PAINT MONO (1395 -225);
FORCEPROP 2 LAST CDS_LIB standard
J 0
(1650 -225);
PAINT MONO (1650 -225);
DISPLAY INVISIBLE (1650 -225);
FORCEPROP 1 LAST OFFPAGE TRUE
J 2
(1325 -350);
DISPLAY 0.872340 (1325 -350);
DISPLAY INVISIBLE (1325 -350);
FORCEPROP 1 LAST COMMENT_BODY TRUE
J 2
(1695 -320);
DISPLAY 0.872340 (1695 -320);
PAINT GREEN (1695 -320);
DISPLAY INVISIBLE (1695 -320);
FORCEPROP 2 LAST PATH I106
J 0
(1375 -175);
DISPLAY 1.021277 (1375 -175);
DISPLAY INVISIBLE (1375 -175);
FORCEADD OFFPAGE..1
(-4225 4300);
FORCEPROP 2 LAST $XR0 236 
J 0
(-4477 4300);
DISPLAY 0.638298 (-4477 4300);
PAINT MONO (-4477 4300);
FORCEPROP 2 LAST CDS_LIB standard
J 0
(-4225 4300);
PAINT MONO (-4225 4300);
DISPLAY INVISIBLE (-4225 4300);
FORCEPROP 1 LAST OFFPAGE TRUE
J 0
(-3900 4175);
DISPLAY 0.872340 (-3900 4175);
DISPLAY INVISIBLE (-3900 4175);
FORCEPROP 1 LAST COMMENT_BODY TRUE
J 0
(-4100 4200);
DISPLAY 0.872340 (-4100 4200);
PAINT GREEN (-4100 4200);
DISPLAY INVISIBLE (-4100 4200);
FORCEPROP 2 LAST PATH I108
J 0
(-4500 4350);
DISPLAY 1.021277 (-4500 4350);
DISPLAY INVISIBLE (-4500 4350);
FORCEADD Q_RES..1
(-3075 4300);
FORCEPROP 1 LAST PART_NUMBER CS03322FB03
J 0
(-3200 4350);
DISPLAY 0.404255 (-3200 4350);
DISPLAY INVISIBLE (-3200 4350);
FORCEPROP 1 LAST PACK_TYPE 0402LF
J 0
(-3200 4400);
DISPLAY 0.404255 (-3200 4400);
FORCEPROP 1 LAST WATTAGE 1/16W
J 2
(-2975 4400);
DISPLAY 0.404255 (-2975 4400);
FORCEPROP 1 LAST MATERIAL CHIP
J 0
(-2775 4300);
DISPLAY 0.404255 (-2775 4300);
FORCEPROP 1 LAST VALUE 33.2
J 2
(-2875 4300);
DISPLAY 0.404255 (-2875 4300);
FORCEPROP 1 LAST TOLERANCE 1%
J 0
(-2850 4300);
DISPLAY 0.404255 (-2850 4300);
FORCEPROP 1 LAST $LOCATION R1932
J 0
(-3300 4300);
DISPLAY 0.638298 (-3300 4300);
FORCEPROP 1 LASTPIN (-3175 4300) $PN 1
J 0
(-3163 4312);
DISPLAY 0.787234 (-3163 4312);
PAINT MONO (-3163 4312);
FORCEPROP 1 LASTPIN (-2975 4300) $PN 2
J 0
(-3013 4312);
DISPLAY 0.787234 (-3013 4312);
PAINT MONO (-3013 4312);
FORCEPROP 2 LAST CDS_LIB pure_quanta
J 0
(-3075 4300);
DISPLAY INVISIBLE (-3075 4300);
FORCEPROP 0 LAST CDS_LOCATION R1932
J 0
(-2975 4425);
DISPLAY 1.021277 (-2975 4425);
DISPLAY INVISIBLE (-2975 4425);
FORCEPROP 0 LAST $SEC 1
J 0
(-2975 4425);
DISPLAY 0.680851 (-2975 4425);
PAINT MONO (-2975 4425);
DISPLAY INVISIBLE (-2975 4425);
FORCEPROP 0 LAST CDS_SEC 1
J 0
(-2975 4425);
DISPLAY 1.021277 (-2975 4425);
DISPLAY INVISIBLE (-2975 4425);
FORCEPROP 1 LAST PATH I109
J 0
(-3125 4450);
DISPLAY 0.978723 (-3125 4450);
PAINT WHITE (-3125 4450);
DISPLAY INVISIBLE (-3125 4450);
FORCEADD OFFPAGE..1
(-2675 3850);
FORCEPROP 2 LAST $XR0 235 
J 0
(-2957 3850);
DISPLAY 0.638298 (-2957 3850);
PAINT MONO (-2957 3850);
FORCEPROP 2 LAST CDS_LIB standard
J 0
(-2675 3850);
PAINT MONO (-2675 3850);
DISPLAY INVISIBLE (-2675 3850);
FORCEPROP 1 LAST OFFPAGE TRUE
J 0
(-2350 3725);
DISPLAY 0.872340 (-2350 3725);
DISPLAY INVISIBLE (-2350 3725);
FORCEPROP 1 LAST COMMENT_BODY TRUE
J 0
(-2550 3750);
DISPLAY 0.872340 (-2550 3750);
PAINT GREEN (-2550 3750);
DISPLAY INVISIBLE (-2550 3750);
FORCEPROP 2 LAST PATH I11
J 0
(-2625 3925);
DISPLAY 1.021277 (-2625 3925);
DISPLAY INVISIBLE (-2625 3925);
FORCEADD Q_RES..1
(-3075 4250);
FORCEPROP 1 LAST PART_NUMBER CS03322FB03
J 0
(-3200 4300);
DISPLAY 0.510638 (-3200 4300);
DISPLAY INVISIBLE (-3200 4300);
FORCEPROP 1 LAST MATERIAL CHIP
J 0
(-2775 4250);
DISPLAY 0.404255 (-2775 4250);
FORCEPROP 1 LAST TOLERANCE 1%
J 0
(-2850 4250);
DISPLAY 0.404255 (-2850 4250);
FORCEPROP 1 LAST VALUE 33.2
J 2
(-2875 4250);
DISPLAY 0.404255 (-2875 4250);
FORCEPROP 1 LAST $LOCATION R1933
J 0
(-3300 4250);
DISPLAY 0.638298 (-3300 4250);
FORCEPROP 1 LASTPIN (-3175 4250) $PN 1
J 0
(-3163 4262);
DISPLAY 0.787234 (-3163 4262);
PAINT MONO (-3163 4262);
FORCEPROP 1 LASTPIN (-2975 4250) $PN 2
J 0
(-3013 4262);
DISPLAY 0.787234 (-3013 4262);
PAINT MONO (-3013 4262);
FORCEPROP 1 LAST WATTAGE 1/16W
J 2
(-2850 4350);
DISPLAY 0.510638 (-2850 4350);
DISPLAY INVISIBLE (-2850 4350);
FORCEPROP 1 LAST PACK_TYPE 0402LF
J 0
(-3200 4350);
DISPLAY 0.510638 (-3200 4350);
DISPLAY INVISIBLE (-3200 4350);
FORCEPROP 2 LAST CDS_LIB pure_quanta
J 0
(-3075 4250);
DISPLAY INVISIBLE (-3075 4250);
FORCEPROP 0 LAST CDS_LOCATION R1933
J 0
(-3325 4300);
DISPLAY 1.021277 (-3325 4300);
DISPLAY INVISIBLE (-3325 4300);
FORCEPROP 0 LAST $SEC 1
J 0
(-3325 4300);
DISPLAY 0.680851 (-3325 4300);
PAINT MONO (-3325 4300);
DISPLAY INVISIBLE (-3325 4300);
FORCEPROP 0 LAST CDS_SEC 1
J 0
(-3325 4300);
DISPLAY 1.021277 (-3325 4300);
DISPLAY INVISIBLE (-3325 4300);
FORCEPROP 1 LAST PATH I110
J 0
(-3125 4400);
DISPLAY 0.978723 (-3125 4400);
PAINT WHITE (-3125 4400);
DISPLAY INVISIBLE (-3125 4400);
FORCEADD OFFPAGE..3
R 2
(-4225 4250);
FORCEPROP 2 LAST $XR0 236 
J 0
(-4505 4250);
DISPLAY 0.638298 (-4505 4250);
PAINT MONO (-4505 4250);
FORCEPROP 2 LAST CDS_LIB standard
J 0
(-4225 4250);
DISPLAY INVISIBLE (-4225 4250);
FORCEPROP 1 LAST OFFPAGE TRUE
J 2
(-4550 4125);
DISPLAY 0.872340 (-4550 4125);
DISPLAY INVISIBLE (-4550 4125);
FORCEPROP 1 LAST COMMENT_BODY TRUE
J 2
(-4175 4150);
DISPLAY 0.872340 (-4175 4150);
PAINT GREEN (-4175 4150);
DISPLAY INVISIBLE (-4175 4150);
FORCEPROP 2 LAST PATH I111
J 0
(-4550 4300);
DISPLAY 1.021277 (-4550 4300);
DISPLAY INVISIBLE (-4550 4300);
FORCEADD OFFPAGE..2
(225 1425);
FORCEPROP 2 LAST $XR0 14 
J 0
(414 1425);
DISPLAY 0.638298 (414 1425);
PAINT MONO (414 1425);
FORCEPROP 2 LAST CDS_LIB standard
J 0
(225 1425);
PAINT MONO (225 1425);
DISPLAY INVISIBLE (225 1425);
FORCEPROP 1 LAST OFFPAGE TRUE
J 0
(550 1300);
DISPLAY 1.170213 (550 1300);
PAINT GREEN (550 1300);
DISPLAY INVISIBLE (550 1300);
FORCEPROP 1 LAST COMMENT_BODY TRUE
J 0
(180 1330);
DISPLAY 1.170213 (180 1330);
PAINT GREEN (180 1330);
DISPLAY INVISIBLE (180 1330);
FORCEPROP 2 LAST PATH I112
J 0
(425 1475);
DISPLAY 1.021277 (425 1475);
DISPLAY INVISIBLE (425 1475);
FORCEADD OFFPAGE..1
(-2850 1425);
FORCEPROP 2 LAST $XR0 14 
J 0
(-3071 1425);
DISPLAY 0.638298 (-3071 1425);
PAINT MONO (-3071 1425);
FORCEPROP 2 LAST CDS_LIB standard
J 0
(-2850 1425);
PAINT MONO (-2850 1425);
DISPLAY INVISIBLE (-2850 1425);
FORCEPROP 1 LAST OFFPAGE TRUE
J 0
(-2525 1300);
DISPLAY 0.872340 (-2525 1300);
DISPLAY INVISIBLE (-2525 1300);
FORCEPROP 1 LAST COMMENT_BODY TRUE
J 0
(-2725 1325);
DISPLAY 0.872340 (-2725 1325);
PAINT GREEN (-2725 1325);
DISPLAY INVISIBLE (-2725 1325);
FORCEPROP 2 LAST PATH I114
J 0
(-3100 1475);
DISPLAY 1.021277 (-3100 1475);
DISPLAY INVISIBLE (-3100 1475);
FORCEADD Q_RES..1
(-1600 1425);
FORCEPROP 1 LAST PART_NUMBER CS00002JB13
J 0
(-1750 1500);
DISPLAY 0.638298 (-1750 1500);
DISPLAY INVISIBLE (-1750 1500);
FORCEPROP 1 LAST WATTAGE 1/16W
J 2
(-1350 1550);
DISPLAY 0.638298 (-1350 1550);
FORCEPROP 1 LAST PACK_TYPE 0402LF
J 0
(-1750 1550);
DISPLAY 0.638298 (-1750 1550);
FORCEPROP 1 LAST VALUE 0
J 2
(-1375 1425);
DISPLAY 0.638298 (-1375 1425);
FORCEPROP 1 LAST MATERIAL CHIP
J 0
(-1200 1425);
DISPLAY 0.638298 (-1200 1425);
FORCEPROP 1 LAST TOLERANCE 5%
J 0
(-1300 1425);
DISPLAY 0.638298 (-1300 1425);
FORCEPROP 1 LAST $LOCATION R1959
J 0
(-1850 1425);
DISPLAY 0.638298 (-1850 1425);
FORCEPROP 1 LASTPIN (-1700 1425) $PN 1
J 0
(-1688 1437);
DISPLAY 0.787234 (-1688 1437);
PAINT MONO (-1688 1437);
FORCEPROP 1 LASTPIN (-1500 1425) $PN 2
J 0
(-1538 1437);
DISPLAY 0.787234 (-1538 1437);
PAINT MONO (-1538 1437);
FORCEPROP 2 LAST CDS_LIB pure_quanta
J 0
(-1600 1425);
DISPLAY INVISIBLE (-1600 1425);
FORCEPROP 0 LAST CDS_LOCATION R1959
J 0
(-1350 1600);
DISPLAY 1.021277 (-1350 1600);
DISPLAY INVISIBLE (-1350 1600);
FORCEPROP 0 LAST $SEC 1
J 0
(-1350 1600);
DISPLAY 0.680851 (-1350 1600);
PAINT MONO (-1350 1600);
DISPLAY INVISIBLE (-1350 1600);
FORCEPROP 0 LAST CDS_SEC 1
J 0
(-1350 1600);
DISPLAY 1.021277 (-1350 1600);
DISPLAY INVISIBLE (-1350 1600);
FORCEPROP 1 LAST PATH I115
J 0
(-1650 1575);
DISPLAY 0.978723 (-1650 1575);
PAINT WHITE (-1650 1575);
DISPLAY INVISIBLE (-1650 1575);
FORCEADD OFFPAGE..2
(225 750);
FORCEPROP 2 LAST $XR0 14 
J 0
(414 750);
DISPLAY 0.638298 (414 750);
PAINT MONO (414 750);
FORCEPROP 2 LAST CDS_LIB standard
J 0
(225 750);
PAINT MONO (225 750);
DISPLAY INVISIBLE (225 750);
FORCEPROP 1 LAST OFFPAGE TRUE
J 0
(550 625);
DISPLAY 1.170213 (550 625);
PAINT GREEN (550 625);
DISPLAY INVISIBLE (550 625);
FORCEPROP 1 LAST COMMENT_BODY TRUE
J 0
(180 655);
DISPLAY 1.170213 (180 655);
PAINT GREEN (180 655);
DISPLAY INVISIBLE (180 655);
FORCEPROP 2 LAST PATH I116
J 0
(425 800);
DISPLAY 1.021277 (425 800);
DISPLAY INVISIBLE (425 800);
FORCEADD Q_RES..1
(-1600 750);
FORCEPROP 1 LAST PART_NUMBER CS00002JB13
J 0
(-1750 825);
DISPLAY 0.638298 (-1750 825);
DISPLAY INVISIBLE (-1750 825);
FORCEPROP 1 LAST TOLERANCE 5%
J 0
(-1300 750);
DISPLAY 0.638298 (-1300 750);
FORCEPROP 1 LAST MATERIAL CHIP
J 0
(-1200 750);
DISPLAY 0.638298 (-1200 750);
FORCEPROP 1 LAST PACK_TYPE 0402LF
J 0
(-1750 875);
DISPLAY 0.638298 (-1750 875);
FORCEPROP 1 LAST WATTAGE 1/16W
J 2
(-1350 875);
DISPLAY 0.638298 (-1350 875);
FORCEPROP 1 LAST VALUE 0
J 2
(-1375 750);
DISPLAY 0.638298 (-1375 750);
FORCEPROP 1 LAST $LOCATION R1960
J 0
(-1850 750);
DISPLAY 0.638298 (-1850 750);
FORCEPROP 1 LASTPIN (-1700 750) $PN 1
J 0
(-1688 762);
DISPLAY 0.787234 (-1688 762);
PAINT MONO (-1688 762);
FORCEPROP 1 LASTPIN (-1500 750) $PN 2
J 0
(-1538 762);
DISPLAY 0.787234 (-1538 762);
PAINT MONO (-1538 762);
FORCEPROP 2 LAST CDS_LIB pure_quanta
J 0
(-1600 750);
DISPLAY INVISIBLE (-1600 750);
FORCEPROP 0 LAST CDS_LOCATION R1960
J 0
(-1350 925);
DISPLAY 1.021277 (-1350 925);
DISPLAY INVISIBLE (-1350 925);
FORCEPROP 0 LAST $SEC 1
J 0
(-1350 925);
DISPLAY 0.680851 (-1350 925);
PAINT MONO (-1350 925);
DISPLAY INVISIBLE (-1350 925);
FORCEPROP 0 LAST CDS_SEC 1
J 0
(-1350 925);
DISPLAY 1.021277 (-1350 925);
DISPLAY INVISIBLE (-1350 925);
FORCEPROP 1 LAST PATH I117
J 0
(-1650 900);
DISPLAY 0.978723 (-1650 900);
PAINT WHITE (-1650 900);
DISPLAY INVISIBLE (-1650 900);
FORCEADD OFFPAGE..1
(-2850 750);
FORCEPROP 2 LAST $XR0 184 
J 0
(-3102 750);
DISPLAY 0.638298 (-3102 750);
PAINT MONO (-3102 750);
FORCEPROP 2 LAST CDS_LIB standard
J 0
(-2850 750);
PAINT MONO (-2850 750);
DISPLAY INVISIBLE (-2850 750);
FORCEPROP 1 LAST OFFPAGE TRUE
J 0
(-2525 625);
DISPLAY 0.872340 (-2525 625);
DISPLAY INVISIBLE (-2525 625);
FORCEPROP 1 LAST COMMENT_BODY TRUE
J 0
(-2725 650);
DISPLAY 0.872340 (-2725 650);
PAINT GREEN (-2725 650);
DISPLAY INVISIBLE (-2725 650);
FORCEPROP 2 LAST PATH I118
J 0
(-3100 800);
DISPLAY 1.021277 (-3100 800);
DISPLAY INVISIBLE (-3100 800);
FORCEADD OFFPAGE..2
R 2
(-2675 3950);
FORCEPROP 2 LAST $XR0 235 
J 0
(-2930 3950);
DISPLAY 0.638298 (-2930 3950);
PAINT MONO (-2930 3950);
FORCEPROP 2 LAST CDS_LIB standard
J 0
(-2675 3950);
PAINT MONO (-2675 3950);
DISPLAY INVISIBLE (-2675 3950);
FORCEPROP 1 LAST OFFPAGE TRUE
J 2
(-3000 3825);
DISPLAY 0.872340 (-3000 3825);
DISPLAY INVISIBLE (-3000 3825);
FORCEPROP 1 LAST COMMENT_BODY TRUE
J 2
(-2630 3855);
DISPLAY 0.872340 (-2630 3855);
PAINT GREEN (-2630 3855);
DISPLAY INVISIBLE (-2630 3855);
FORCEPROP 2 LAST PATH I12
J 0
(-2625 4025);
DISPLAY 1.021277 (-2625 4025);
DISPLAY INVISIBLE (-2625 4025);
FORCEADD Q_RES..1
(-1600 25);
FORCEPROP 1 LAST PART_NUMBER CS03322FB03
J 0
(-1750 125);
DISPLAY 0.638298 (-1750 125);
DISPLAY INVISIBLE (-1750 125);
FORCEPROP 1 LAST VALUE 33.2
J 2
(-1350 25);
DISPLAY 0.638298 (-1350 25);
FORCEPROP 1 LAST TOLERANCE 1%
J 0
(-1325 25);
DISPLAY 0.638298 (-1325 25);
FORCEPROP 1 LAST WATTAGE 1/16W
J 2
(-1375 175);
DISPLAY 0.638298 (-1375 175);
FORCEPROP 1 LAST MATERIAL CHIP
J 0
(-1225 25);
DISPLAY 0.638298 (-1225 25);
FORCEPROP 1 LAST PACK_TYPE 0402LF
J 0
(-1750 175);
DISPLAY 0.638298 (-1750 175);
FORCEPROP 1 LAST $LOCATION R2362
J 0
(-1850 25);
DISPLAY 0.638298 (-1850 25);
FORCEPROP 2 LAST CDS_LIB pure_quanta
J 0
(-1600 25);
DISPLAY INVISIBLE (-1600 25);
FORCEPROP 0 LAST CDS_LOCATION R2362
J 0
(-1375 225);
DISPLAY 1.021277 (-1375 225);
DISPLAY INVISIBLE (-1375 225);
FORCEPROP 0 LAST $SEC 1
J 0
(-1375 225);
DISPLAY 0.680851 (-1375 225);
PAINT MONO (-1375 225);
DISPLAY INVISIBLE (-1375 225);
FORCEPROP 0 LAST CDS_SEC 1
J 0
(-1375 225);
DISPLAY 1.021277 (-1375 225);
DISPLAY INVISIBLE (-1375 225);
FORCEPROP 1 LASTPIN (-1700 25) $PN 1
J 0
(-1688 37);
DISPLAY 0.787234 (-1688 37);
PAINT MONO (-1688 37);
DISPLAY INVISIBLE (-1688 37);
FORCEPROP 1 LASTPIN (-1500 25) $PN 2
J 0
(-1538 37);
DISPLAY 0.787234 (-1538 37);
PAINT MONO (-1538 37);
DISPLAY INVISIBLE (-1538 37);
FORCEPROP 1 LAST PATH I122
J 0
(-1650 175);
DISPLAY 0.978723 (-1650 175);
PAINT WHITE (-1650 175);
DISPLAY INVISIBLE (-1650 175);
FORCEADD OFFPAGE..1
(-2850 25);
FORCEPROP 2 LAST $XR0 14 
J 0
(-3071 25);
DISPLAY 0.638298 (-3071 25);
PAINT MONO (-3071 25);
FORCEPROP 2 LAST CDS_LIB standard
J 0
(-2850 25);
DISPLAY INVISIBLE (-2850 25);
FORCEPROP 1 LAST OFFPAGE TRUE
J 0
(-2525 -100);
DISPLAY 0.872340 (-2525 -100);
DISPLAY INVISIBLE (-2525 -100);
FORCEPROP 1 LAST COMMENT_BODY TRUE
J 0
(-2725 -75);
DISPLAY 0.872340 (-2725 -75);
PAINT GREEN (-2725 -75);
DISPLAY INVISIBLE (-2725 -75);
FORCEPROP 2 LAST PATH I123
J 0
(-3100 75);
DISPLAY 1.021277 (-3100 75);
DISPLAY INVISIBLE (-3100 75);
FORCEADD OFFPAGE..2
(225 25);
FORCEPROP 2 LAST $XR0 14 
J 0
(414 25);
DISPLAY 0.638298 (414 25);
PAINT MONO (414 25);
FORCEPROP 2 LAST CDS_LIB standard
J 0
(225 25);
DISPLAY INVISIBLE (225 25);
FORCEPROP 1 LAST OFFPAGE TRUE
J 0
(550 -100);
DISPLAY 1.170213 (550 -100);
PAINT GREEN (550 -100);
DISPLAY INVISIBLE (550 -100);
FORCEPROP 1 LAST COMMENT_BODY TRUE
J 0
(180 -70);
DISPLAY 1.170213 (180 -70);
PAINT GREEN (180 -70);
DISPLAY INVISIBLE (180 -70);
FORCEPROP 2 LAST PATH I124
J 0
(425 75);
DISPLAY 1.021277 (425 75);
DISPLAY INVISIBLE (425 75);
FORCEADD OFFPAGE..1
(-2850 -225);
FORCEPROP 2 LAST $XR0 14 
J 0
(-3071 -225);
DISPLAY 0.638298 (-3071 -225);
PAINT MONO (-3071 -225);
FORCEPROP 2 LAST CDS_LIB standard
J 0
(-2850 -225);
DISPLAY INVISIBLE (-2850 -225);
FORCEPROP 1 LAST OFFPAGE TRUE
J 0
(-2525 -350);
DISPLAY 0.872340 (-2525 -350);
DISPLAY INVISIBLE (-2525 -350);
FORCEPROP 1 LAST COMMENT_BODY TRUE
J 0
(-2725 -325);
DISPLAY 0.872340 (-2725 -325);
PAINT GREEN (-2725 -325);
DISPLAY INVISIBLE (-2725 -325);
FORCEPROP 2 LAST PATH I125
J 0
(-3100 -175);
DISPLAY 1.021277 (-3100 -175);
DISPLAY INVISIBLE (-3100 -175);
FORCEADD OFFPAGE..2
(225 -225);
FORCEPROP 2 LAST $XR0 45 
J 0
(414 -225);
DISPLAY 0.638298 (414 -225);
PAINT MONO (414 -225);
FORCEPROP 2 LAST CDS_LIB standard
J 0
(225 -225);
DISPLAY INVISIBLE (225 -225);
FORCEPROP 1 LAST OFFPAGE TRUE
J 0
(550 -350);
DISPLAY 1.170213 (550 -350);
PAINT GREEN (550 -350);
DISPLAY INVISIBLE (550 -350);
FORCEPROP 1 LAST COMMENT_BODY TRUE
J 0
(180 -320);
DISPLAY 1.170213 (180 -320);
PAINT GREEN (180 -320);
DISPLAY INVISIBLE (180 -320);
FORCEPROP 2 LAST PATH I126
J 0
(425 -175);
DISPLAY 1.021277 (425 -175);
DISPLAY INVISIBLE (425 -175);
FORCEADD OFFPAGE..4
(225 -725);
FORCEPROP 2 LAST $XR0 45 
J 0
(411 -725);
DISPLAY 0.638298 (411 -725);
PAINT MONO (411 -725);
FORCEPROP 2 LAST CDS_LIB standard
J 0
(225 -725);
PAINT MONO (225 -725);
DISPLAY INVISIBLE (225 -725);
FORCEPROP 1 LAST OFFPAGE TRUE
J 0
(550 -850);
DISPLAY 1.170213 (550 -850);
PAINT GREEN (550 -850);
DISPLAY INVISIBLE (550 -850);
FORCEPROP 1 LAST COMMENT_BODY TRUE
J 0
(200 -825);
DISPLAY 1.170213 (200 -825);
PAINT GREEN (200 -825);
DISPLAY INVISIBLE (200 -825);
FORCEPROP 2 LAST PATH I127
J 0
(425 -675);
DISPLAY 1.021277 (425 -675);
DISPLAY INVISIBLE (425 -675);
FORCEADD Q_RES..1
(-1600 -725);
FORCEPROP 1 LAST PART_NUMBER CS03322FB03
J 0
(-1750 -625);
DISPLAY 0.638298 (-1750 -625);
DISPLAY INVISIBLE (-1750 -625);
FORCEPROP 1 LAST MATERIAL CHIP
J 0
(-1225 -725);
DISPLAY 0.638298 (-1225 -725);
FORCEPROP 1 LAST TOLERANCE 1%
J 0
(-1325 -725);
DISPLAY 0.638298 (-1325 -725);
FORCEPROP 1 LAST WATTAGE 1/16W
J 2
(-1400 -575);
DISPLAY 0.638298 (-1400 -575);
FORCEPROP 1 LAST VALUE 33.2
J 2
(-1350 -725);
DISPLAY 0.638298 (-1350 -725);
FORCEPROP 1 LAST PACK_TYPE 0402LF
J 0
(-1750 -575);
DISPLAY 0.638298 (-1750 -575);
FORCEPROP 1 LAST $LOCATION R4089
J 0
(-1850 -725);
DISPLAY 0.638298 (-1850 -725);
FORCEPROP 1 LASTPIN (-1700 -725) $PN 1
J 0
(-1688 -713);
DISPLAY 0.787234 (-1688 -713);
FORCEPROP 1 LASTPIN (-1500 -725) $PN 2
J 0
(-1538 -713);
DISPLAY 0.787234 (-1538 -713);
FORCEPROP 2 LAST CDS_LIB pure_quanta
J 0
(-1600 -725);
PAINT MONO (-1600 -725);
DISPLAY INVISIBLE (-1600 -725);
FORCEPROP 2 LAST CDS_LOCATION R4089
J 0
(-1400 -525);
DISPLAY 1.021277 (-1400 -525);
DISPLAY INVISIBLE (-1400 -525);
FORCEPROP 2 LAST $SEC 1
J 0
(-1400 -525);
DISPLAY 0.680851 (-1400 -525);
PAINT MONO (-1400 -525);
DISPLAY INVISIBLE (-1400 -525);
FORCEPROP 2 LAST CDS_SEC 1
J 0
(-1400 -525);
DISPLAY 1.021277 (-1400 -525);
DISPLAY INVISIBLE (-1400 -525);
FORCEPROP 1 LAST PATH I128
J 0
(-1650 -575);
DISPLAY 0.978723 (-1650 -575);
PAINT WHITE (-1650 -575);
DISPLAY INVISIBLE (-1650 -575);
FORCEADD OFFPAGE..2
R 2
(-2850 -725);
FORCEPROP 2 LAST $XR0 14 
J 0
(-3074 -725);
DISPLAY 0.638298 (-3074 -725);
PAINT MONO (-3074 -725);
FORCEPROP 2 LAST CDS_LIB standard
J 0
(-2850 -725);
PAINT MONO (-2850 -725);
DISPLAY INVISIBLE (-2850 -725);
FORCEPROP 1 LAST OFFPAGE TRUE
J 2
(-3175 -850);
DISPLAY 0.872340 (-3175 -850);
DISPLAY INVISIBLE (-3175 -850);
FORCEPROP 1 LAST COMMENT_BODY TRUE
J 2
(-2805 -820);
DISPLAY 0.872340 (-2805 -820);
PAINT GREEN (-2805 -820);
DISPLAY INVISIBLE (-2805 -820);
FORCEPROP 2 LAST PATH I129
J 0
(-3050 -675);
DISPLAY 1.021277 (-3050 -675);
DISPLAY INVISIBLE (-3050 -675);
FORCEADD OFFPAGE..1
(-2675 3750);
FORCEPROP 2 LAST $XR0 119 
J 0
(-2957 3750);
DISPLAY 0.638298 (-2957 3750);
PAINT MONO (-2957 3750);
FORCEPROP 2 LAST CDS_LIB standard
J 0
(-2675 3750);
PAINT MONO (-2675 3750);
DISPLAY INVISIBLE (-2675 3750);
FORCEPROP 1 LAST OFFPAGE TRUE
J 0
(-2350 3625);
DISPLAY 0.872340 (-2350 3625);
DISPLAY INVISIBLE (-2350 3625);
FORCEPROP 1 LAST COMMENT_BODY TRUE
J 0
(-2550 3650);
DISPLAY 0.872340 (-2550 3650);
PAINT GREEN (-2550 3650);
DISPLAY INVISIBLE (-2550 3650);
FORCEPROP 2 LAST PATH I13
J 0
(-2625 3825);
DISPLAY 1.021277 (-2625 3825);
DISPLAY INVISIBLE (-2625 3825);
FORCEADD OFFPAGE..2
R 2
(-2675 3650);
FORCEPROP 2 LAST $XR1 222 
J 0
(-3050 3650);
DISPLAY 0.638298 (-3050 3650);
PAINT MONO (-3050 3650);
FORCEPROP 2 LAST $XR0 133 
J 0
(-2930 3650);
DISPLAY 0.638298 (-2930 3650);
PAINT MONO (-2930 3650);
FORCEPROP 2 LAST CDS_LIB standard
J 0
(-2675 3650);
PAINT MONO (-2675 3650);
DISPLAY INVISIBLE (-2675 3650);
FORCEPROP 1 LAST OFFPAGE TRUE
J 2
(-3000 3525);
DISPLAY 0.872340 (-3000 3525);
DISPLAY INVISIBLE (-3000 3525);
FORCEPROP 1 LAST COMMENT_BODY TRUE
J 2
(-2630 3555);
DISPLAY 0.872340 (-2630 3555);
PAINT GREEN (-2630 3555);
DISPLAY INVISIBLE (-2630 3555);
FORCEPROP 2 LAST PATH I14
J 0
(-2625 3725);
DISPLAY 1.021277 (-2625 3725);
DISPLAY INVISIBLE (-2625 3725);
FORCEADD OFFPAGE..1
(-2675 3600);
FORCEPROP 2 LAST $XR0 119 
J 0
(-2957 3600);
DISPLAY 0.638298 (-2957 3600);
PAINT MONO (-2957 3600);
FORCEPROP 2 LAST CDS_LIB standard
J 0
(-2675 3600);
PAINT MONO (-2675 3600);
DISPLAY INVISIBLE (-2675 3600);
FORCEPROP 1 LAST OFFPAGE TRUE
J 0
(-2350 3475);
DISPLAY 0.872340 (-2350 3475);
DISPLAY INVISIBLE (-2350 3475);
FORCEPROP 1 LAST COMMENT_BODY TRUE
J 0
(-2550 3500);
DISPLAY 0.872340 (-2550 3500);
PAINT GREEN (-2550 3500);
DISPLAY INVISIBLE (-2550 3500);
FORCEPROP 2 LAST PATH I15
J 0
(-2625 3675);
DISPLAY 1.021277 (-2625 3675);
DISPLAY INVISIBLE (-2625 3675);
FORCEADD OFFPAGE..1
(-2675 3300);
FORCEPROP 2 LAST $XR0 14 
J 0
(-2926 3300);
DISPLAY 0.638298 (-2926 3300);
PAINT MONO (-2926 3300);
FORCEPROP 2 LAST CDS_LIB standard
J 0
(-2675 3300);
PAINT MONO (-2675 3300);
DISPLAY INVISIBLE (-2675 3300);
FORCEPROP 1 LAST OFFPAGE TRUE
J 0
(-2350 3175);
DISPLAY 0.872340 (-2350 3175);
DISPLAY INVISIBLE (-2350 3175);
FORCEPROP 1 LAST COMMENT_BODY TRUE
J 0
(-2550 3200);
DISPLAY 0.872340 (-2550 3200);
PAINT GREEN (-2550 3200);
DISPLAY INVISIBLE (-2550 3200);
FORCEPROP 2 LAST PATH I16
J 0
(-2625 3375);
DISPLAY 1.021277 (-2625 3375);
DISPLAY INVISIBLE (-2625 3375);
FORCEADD OFFPAGE..2
R 2
(-2675 3250);
FORCEPROP 2 LAST $XR0 14 
J 0
(-2899 3250);
DISPLAY 0.638298 (-2899 3250);
PAINT MONO (-2899 3250);
FORCEPROP 2 LAST CDS_LIB standard
J 0
(-2675 3250);
PAINT MONO (-2675 3250);
DISPLAY INVISIBLE (-2675 3250);
FORCEPROP 1 LAST OFFPAGE TRUE
J 2
(-3000 3125);
DISPLAY 0.872340 (-3000 3125);
DISPLAY INVISIBLE (-3000 3125);
FORCEPROP 1 LAST COMMENT_BODY TRUE
J 2
(-2630 3155);
DISPLAY 0.872340 (-2630 3155);
PAINT GREEN (-2630 3155);
DISPLAY INVISIBLE (-2630 3155);
FORCEPROP 2 LAST PATH I17
J 0
(-2625 3325);
DISPLAY 1.021277 (-2625 3325);
DISPLAY INVISIBLE (-2625 3325);
FORCEADD OFFPAGE..2
R 2
(-2675 3150);
FORCEPROP 2 LAST $XR0 14 
J 0
(-2899 3150);
DISPLAY 0.638298 (-2899 3150);
PAINT MONO (-2899 3150);
FORCEPROP 2 LAST CDS_LIB standard
J 0
(-2675 3150);
PAINT MONO (-2675 3150);
DISPLAY INVISIBLE (-2675 3150);
FORCEPROP 1 LAST OFFPAGE TRUE
J 2
(-3000 3025);
DISPLAY 0.872340 (-3000 3025);
DISPLAY INVISIBLE (-3000 3025);
FORCEPROP 1 LAST COMMENT_BODY TRUE
J 2
(-2630 3055);
DISPLAY 0.872340 (-2630 3055);
PAINT GREEN (-2630 3055);
DISPLAY INVISIBLE (-2630 3055);
FORCEPROP 2 LAST PATH I18
J 0
(-2625 3225);
DISPLAY 1.021277 (-2625 3225);
DISPLAY INVISIBLE (-2625 3225);
FORCEADD OFFPAGE..1
(-2675 3200);
FORCEPROP 2 LAST $XR0 14 
J 0
(-2926 3200);
DISPLAY 0.638298 (-2926 3200);
PAINT MONO (-2926 3200);
FORCEPROP 2 LAST CDS_LIB standard
J 0
(-2675 3200);
PAINT MONO (-2675 3200);
DISPLAY INVISIBLE (-2675 3200);
FORCEPROP 1 LAST OFFPAGE TRUE
J 0
(-2350 3075);
DISPLAY 0.872340 (-2350 3075);
DISPLAY INVISIBLE (-2350 3075);
FORCEPROP 1 LAST COMMENT_BODY TRUE
J 0
(-2550 3100);
DISPLAY 0.872340 (-2550 3100);
PAINT GREEN (-2550 3100);
DISPLAY INVISIBLE (-2550 3100);
FORCEPROP 2 LAST PATH I19
J 0
(-2625 3275);
DISPLAY 1.021277 (-2625 3275);
DISPLAY INVISIBLE (-2625 3275);
FORCEADD OFFPAGE..1
(-2675 2300);
FORCEPROP 2 LAST $XR0 124 
J 0
(-2957 2300);
DISPLAY 0.638298 (-2957 2300);
PAINT MONO (-2957 2300);
FORCEPROP 2 LAST CDS_LIB standard
J 0
(-2675 2300);
PAINT MONO (-2675 2300);
DISPLAY INVISIBLE (-2675 2300);
FORCEPROP 1 LAST OFFPAGE TRUE
J 0
(-2350 2175);
DISPLAY 0.872340 (-2350 2175);
DISPLAY INVISIBLE (-2350 2175);
FORCEPROP 1 LAST COMMENT_BODY TRUE
J 0
(-2550 2200);
DISPLAY 0.872340 (-2550 2200);
PAINT GREEN (-2550 2200);
DISPLAY INVISIBLE (-2550 2200);
FORCEPROP 2 LAST PATH I20
J 0
(-2625 2375);
DISPLAY 1.021277 (-2625 2375);
DISPLAY INVISIBLE (-2625 2375);
FORCEADD OFFPAGE..1
(-2675 2250);
FORCEPROP 2 LAST $XR0 124 
J 0
(-2957 2250);
DISPLAY 0.638298 (-2957 2250);
PAINT MONO (-2957 2250);
FORCEPROP 2 LAST CDS_LIB standard
J 0
(-2675 2250);
PAINT MONO (-2675 2250);
DISPLAY INVISIBLE (-2675 2250);
FORCEPROP 1 LAST OFFPAGE TRUE
J 0
(-2350 2125);
DISPLAY 0.872340 (-2350 2125);
DISPLAY INVISIBLE (-2350 2125);
FORCEPROP 1 LAST COMMENT_BODY TRUE
J 0
(-2550 2150);
DISPLAY 0.872340 (-2550 2150);
PAINT GREEN (-2550 2150);
DISPLAY INVISIBLE (-2550 2150);
FORCEPROP 2 LAST PATH I21
J 0
(-2625 2325);
DISPLAY 1.021277 (-2625 2325);
DISPLAY INVISIBLE (-2625 2325);
FORCEADD OFFPAGE..1
(-2675 2200);
FORCEPROP 2 LAST $XR0 124 
J 0
(-2957 2200);
DISPLAY 0.638298 (-2957 2200);
PAINT MONO (-2957 2200);
FORCEPROP 2 LAST CDS_LIB standard
J 0
(-2675 2200);
PAINT MONO (-2675 2200);
DISPLAY INVISIBLE (-2675 2200);
FORCEPROP 1 LAST OFFPAGE TRUE
J 0
(-2350 2075);
DISPLAY 0.872340 (-2350 2075);
DISPLAY INVISIBLE (-2350 2075);
FORCEPROP 1 LAST COMMENT_BODY TRUE
J 0
(-2550 2100);
DISPLAY 0.872340 (-2550 2100);
PAINT GREEN (-2550 2100);
DISPLAY INVISIBLE (-2550 2100);
FORCEPROP 2 LAST PATH I22
J 0
(-2625 2275);
DISPLAY 1.021277 (-2625 2275);
DISPLAY INVISIBLE (-2625 2275);
FORCEADD OFFPAGE..1
(-2675 2150);
FORCEPROP 2 LAST $XR0 124 
J 0
(-2957 2150);
DISPLAY 0.638298 (-2957 2150);
PAINT MONO (-2957 2150);
FORCEPROP 2 LAST CDS_LIB standard
J 0
(-2675 2150);
PAINT MONO (-2675 2150);
DISPLAY INVISIBLE (-2675 2150);
FORCEPROP 1 LAST OFFPAGE TRUE
J 0
(-2350 2025);
DISPLAY 0.872340 (-2350 2025);
DISPLAY INVISIBLE (-2350 2025);
FORCEPROP 1 LAST COMMENT_BODY TRUE
J 0
(-2550 2050);
DISPLAY 0.872340 (-2550 2050);
PAINT GREEN (-2550 2050);
DISPLAY INVISIBLE (-2550 2050);
FORCEPROP 2 LAST PATH I23
J 0
(-2625 2225);
DISPLAY 1.021277 (-2625 2225);
DISPLAY INVISIBLE (-2625 2225);
FORCEADD OFFPAGE..1
(-2675 2100);
FORCEPROP 2 LAST $XR0 124 
J 0
(-2957 2100);
DISPLAY 0.638298 (-2957 2100);
PAINT MONO (-2957 2100);
FORCEPROP 2 LAST CDS_LIB standard
J 0
(-2675 2100);
PAINT MONO (-2675 2100);
DISPLAY INVISIBLE (-2675 2100);
FORCEPROP 1 LAST OFFPAGE TRUE
J 0
(-2350 1975);
DISPLAY 0.872340 (-2350 1975);
DISPLAY INVISIBLE (-2350 1975);
FORCEPROP 1 LAST COMMENT_BODY TRUE
J 0
(-2550 2000);
DISPLAY 0.872340 (-2550 2000);
PAINT GREEN (-2550 2000);
DISPLAY INVISIBLE (-2550 2000);
FORCEPROP 2 LAST PATH I24
J 0
(-2625 2175);
DISPLAY 1.021277 (-2625 2175);
DISPLAY INVISIBLE (-2625 2175);
FORCEADD OFFPAGE..1
(-2675 2000);
FORCEPROP 2 LAST $XR0 124 
J 0
(-2957 2000);
DISPLAY 0.638298 (-2957 2000);
PAINT MONO (-2957 2000);
FORCEPROP 2 LAST CDS_LIB standard
J 0
(-2675 2000);
PAINT MONO (-2675 2000);
DISPLAY INVISIBLE (-2675 2000);
FORCEPROP 1 LAST OFFPAGE TRUE
J 0
(-2350 1875);
DISPLAY 0.872340 (-2350 1875);
DISPLAY INVISIBLE (-2350 1875);
FORCEPROP 1 LAST COMMENT_BODY TRUE
J 0
(-2550 1900);
DISPLAY 0.872340 (-2550 1900);
PAINT GREEN (-2550 1900);
DISPLAY INVISIBLE (-2550 1900);
FORCEPROP 2 LAST PATH I25
J 0
(-2625 2075);
DISPLAY 1.021277 (-2625 2075);
DISPLAY INVISIBLE (-2625 2075);
FORCEADD OFFPAGE..2
(2600 4000);
FORCEPROP 2 LAST $XR0 225 
J 0
(2789 4000);
DISPLAY 0.638298 (2789 4000);
PAINT MONO (2789 4000);
FORCEPROP 2 LAST CDS_LIB standard
J 0
(2600 4000);
PAINT MONO (2600 4000);
DISPLAY INVISIBLE (2600 4000);
FORCEPROP 1 LAST OFFPAGE TRUE
J 0
(2925 3875);
DISPLAY 1.170213 (2925 3875);
PAINT GREEN (2925 3875);
DISPLAY INVISIBLE (2925 3875);
FORCEPROP 1 LAST COMMENT_BODY TRUE
J 0
(2555 3905);
DISPLAY 1.170213 (2555 3905);
PAINT GREEN (2555 3905);
DISPLAY INVISIBLE (2555 3905);
FORCEPROP 2 LAST PATH I26
J 0
(2775 4075);
DISPLAY 1.021277 (2775 4075);
DISPLAY INVISIBLE (2775 4075);
FORCEADD OFFPAGE..2
(2600 4050);
FORCEPROP 2 LAST $XR0 225 
J 0
(2789 4050);
DISPLAY 0.638298 (2789 4050);
PAINT MONO (2789 4050);
FORCEPROP 2 LAST CDS_LIB standard
J 0
(2600 4050);
PAINT MONO (2600 4050);
DISPLAY INVISIBLE (2600 4050);
FORCEPROP 1 LAST OFFPAGE TRUE
J 0
(2925 3925);
DISPLAY 1.170213 (2925 3925);
PAINT GREEN (2925 3925);
DISPLAY INVISIBLE (2925 3925);
FORCEPROP 1 LAST COMMENT_BODY TRUE
J 0
(2555 3955);
DISPLAY 1.170213 (2555 3955);
PAINT GREEN (2555 3955);
DISPLAY INVISIBLE (2555 3955);
FORCEPROP 2 LAST PATH I27
J 0
(2775 4125);
DISPLAY 1.021277 (2775 4125);
DISPLAY INVISIBLE (2775 4125);
FORCEADD OFFPAGE..2
(2600 4100);
FORCEPROP 2 LAST $XR0 225 
J 0
(2789 4100);
DISPLAY 0.638298 (2789 4100);
PAINT MONO (2789 4100);
FORCEPROP 2 LAST CDS_LIB standard
J 0
(2600 4100);
PAINT MONO (2600 4100);
DISPLAY INVISIBLE (2600 4100);
FORCEPROP 1 LAST OFFPAGE TRUE
J 0
(2925 3975);
DISPLAY 1.170213 (2925 3975);
PAINT GREEN (2925 3975);
DISPLAY INVISIBLE (2925 3975);
FORCEPROP 1 LAST COMMENT_BODY TRUE
J 0
(2555 4005);
DISPLAY 1.170213 (2555 4005);
PAINT GREEN (2555 4005);
DISPLAY INVISIBLE (2555 4005);
FORCEPROP 2 LAST PATH I28
J 0
(2775 4175);
DISPLAY 1.021277 (2775 4175);
DISPLAY INVISIBLE (2775 4175);
FORCEADD OFFPAGE..2
(2600 3750);
FORCEPROP 2 LAST $XR0 122 
J 0
(2789 3750);
DISPLAY 0.638298 (2789 3750);
PAINT MONO (2789 3750);
FORCEPROP 2 LAST CDS_LIB standard
J 0
(2600 3750);
PAINT MONO (2600 3750);
DISPLAY INVISIBLE (2600 3750);
FORCEPROP 1 LAST OFFPAGE TRUE
J 0
(2925 3625);
DISPLAY 1.170213 (2925 3625);
PAINT GREEN (2925 3625);
DISPLAY INVISIBLE (2925 3625);
FORCEPROP 1 LAST COMMENT_BODY TRUE
J 0
(2555 3655);
DISPLAY 1.170213 (2555 3655);
PAINT GREEN (2555 3655);
DISPLAY INVISIBLE (2555 3655);
FORCEPROP 2 LAST PATH I32
J 0
(2775 3825);
DISPLAY 1.021277 (2775 3825);
DISPLAY INVISIBLE (2775 3825);
FORCEADD OFFPAGE..2
(2600 3700);
FORCEPROP 2 LAST $XR0 123 
J 0
(2789 3700);
DISPLAY 0.638298 (2789 3700);
PAINT MONO (2789 3700);
FORCEPROP 2 LAST CDS_LIB standard
J 0
(2600 3700);
PAINT MONO (2600 3700);
DISPLAY INVISIBLE (2600 3700);
FORCEPROP 1 LAST OFFPAGE TRUE
J 0
(2925 3575);
DISPLAY 1.170213 (2925 3575);
PAINT GREEN (2925 3575);
DISPLAY INVISIBLE (2925 3575);
FORCEPROP 1 LAST COMMENT_BODY TRUE
J 0
(2555 3605);
DISPLAY 1.170213 (2555 3605);
PAINT GREEN (2555 3605);
DISPLAY INVISIBLE (2555 3605);
FORCEPROP 2 LAST PATH I33
J 0
(2775 3775);
DISPLAY 1.021277 (2775 3775);
DISPLAY INVISIBLE (2775 3775);
FORCEADD OFFPAGE..2
(2600 3650);
FORCEPROP 2 LAST $XR0 121 
J 0
(2789 3650);
DISPLAY 0.638298 (2789 3650);
PAINT MONO (2789 3650);
FORCEPROP 2 LAST CDS_LIB standard
J 0
(2600 3650);
PAINT MONO (2600 3650);
DISPLAY INVISIBLE (2600 3650);
FORCEPROP 1 LAST OFFPAGE TRUE
J 0
(2925 3525);
DISPLAY 1.170213 (2925 3525);
PAINT GREEN (2925 3525);
DISPLAY INVISIBLE (2925 3525);
FORCEPROP 1 LAST COMMENT_BODY TRUE
J 0
(2555 3555);
DISPLAY 1.170213 (2555 3555);
PAINT GREEN (2555 3555);
DISPLAY INVISIBLE (2555 3555);
FORCEPROP 2 LAST PATH I34
J 0
(2775 3725);
DISPLAY 1.021277 (2775 3725);
DISPLAY INVISIBLE (2775 3725);
FORCEADD OFFPAGE..4
(2600 3450);
FORCEPROP 2 LAST $XR1 45 
J 0
(2906 3450);
DISPLAY 0.638298 (2906 3450);
PAINT MONO (2906 3450);
FORCEPROP 2 LAST $XR0 131 
J 0
(2786 3450);
DISPLAY 0.638298 (2786 3450);
PAINT MONO (2786 3450);
FORCEPROP 2 LAST CDS_LIB standard
J 0
(2600 3450);
PAINT MONO (2600 3450);
DISPLAY INVISIBLE (2600 3450);
FORCEPROP 1 LAST OFFPAGE TRUE
J 0
(2925 3325);
DISPLAY 1.170213 (2925 3325);
PAINT GREEN (2925 3325);
DISPLAY INVISIBLE (2925 3325);
FORCEPROP 1 LAST COMMENT_BODY TRUE
J 0
(2575 3350);
DISPLAY 1.170213 (2575 3350);
PAINT GREEN (2575 3350);
DISPLAY INVISIBLE (2575 3350);
FORCEPROP 2 LAST PATH I39
J 0
(2775 3525);
DISPLAY 1.021277 (2775 3525);
DISPLAY INVISIBLE (2775 3525);
FORCEADD OFFPAGE..3
(2600 3350);
FORCEPROP 2 LAST $XR0 117 
J 0
(2814 3350);
DISPLAY 0.638298 (2814 3350);
PAINT MONO (2814 3350);
FORCEPROP 2 LAST CDS_LIB standard
J 0
(2600 3350);
PAINT MONO (2600 3350);
DISPLAY INVISIBLE (2600 3350);
FORCEPROP 1 LAST OFFPAGE TRUE
J 0
(2925 3225);
DISPLAY 1.170213 (2925 3225);
PAINT GREEN (2925 3225);
DISPLAY INVISIBLE (2925 3225);
FORCEPROP 1 LAST COMMENT_BODY TRUE
J 0
(2550 3250);
DISPLAY 1.170213 (2550 3250);
PAINT GREEN (2550 3250);
DISPLAY INVISIBLE (2550 3250);
FORCEPROP 2 LAST PATH I40
J 0
(2975 3400);
DISPLAY 1.021277 (2975 3400);
DISPLAY INVISIBLE (2975 3400);
FORCEADD OFFPAGE..4
(2600 3600);
FORCEPROP 2 LAST $XR0 123 
J 0
(2786 3600);
DISPLAY 0.638298 (2786 3600);
PAINT MONO (2786 3600);
FORCEPROP 2 LAST CDS_LIB standard
J 0
(2600 3600);
PAINT MONO (2600 3600);
DISPLAY INVISIBLE (2600 3600);
FORCEPROP 1 LAST OFFPAGE TRUE
J 0
(2925 3475);
DISPLAY 1.170213 (2925 3475);
PAINT GREEN (2925 3475);
DISPLAY INVISIBLE (2925 3475);
FORCEPROP 1 LAST COMMENT_BODY TRUE
J 0
(2575 3500);
DISPLAY 1.170213 (2575 3500);
PAINT GREEN (2575 3500);
DISPLAY INVISIBLE (2575 3500);
FORCEPROP 2 LAST PATH I41
J 0
(2775 3675);
DISPLAY 1.021277 (2775 3675);
DISPLAY INVISIBLE (2775 3675);
FORCEADD OFFPAGE..4
(2600 3850);
FORCEPROP 2 LAST $XR0 121 
J 0
(2816 3850);
DISPLAY 0.638298 (2816 3850);
PAINT MONO (2816 3850);
FORCEPROP 2 LAST CDS_LIB standard
J 0
(2600 3850);
PAINT MONO (2600 3850);
DISPLAY INVISIBLE (2600 3850);
FORCEPROP 1 LAST OFFPAGE TRUE
J 0
(2925 3725);
DISPLAY 1.170213 (2925 3725);
PAINT GREEN (2925 3725);
DISPLAY INVISIBLE (2925 3725);
FORCEPROP 1 LAST COMMENT_BODY TRUE
J 0
(2575 3750);
DISPLAY 1.170213 (2575 3750);
PAINT GREEN (2575 3750);
DISPLAY INVISIBLE (2575 3750);
FORCEPROP 2 LAST PATH I42
J 0
(2775 3925);
DISPLAY 1.021277 (2775 3925);
DISPLAY INVISIBLE (2775 3925);
FORCEADD OFFPAGE..4
(2600 3800);
FORCEPROP 2 LAST $XR0 122 
J 0
(2786 3800);
DISPLAY 0.638298 (2786 3800);
PAINT MONO (2786 3800);
FORCEPROP 2 LAST CDS_LIB standard
J 0
(2600 3800);
PAINT MONO (2600 3800);
DISPLAY INVISIBLE (2600 3800);
FORCEPROP 1 LAST OFFPAGE TRUE
J 0
(2925 3675);
DISPLAY 1.170213 (2925 3675);
PAINT GREEN (2925 3675);
DISPLAY INVISIBLE (2925 3675);
FORCEPROP 1 LAST COMMENT_BODY TRUE
J 0
(2575 3700);
DISPLAY 1.170213 (2575 3700);
PAINT GREEN (2575 3700);
DISPLAY INVISIBLE (2575 3700);
FORCEPROP 2 LAST PATH I43
J 0
(2775 3875);
DISPLAY 1.021277 (2775 3875);
DISPLAY INVISIBLE (2775 3875);
FORCEADD OFFPAGE..3
(2600 3900);
FORCEPROP 2 LAST $XR0 118 
J 0
(2814 3900);
DISPLAY 0.638298 (2814 3900);
PAINT MONO (2814 3900);
FORCEPROP 2 LAST CDS_LIB standard
J 0
(2600 3900);
PAINT MONO (2600 3900);
DISPLAY INVISIBLE (2600 3900);
FORCEPROP 1 LAST OFFPAGE TRUE
J 0
(2925 3775);
DISPLAY 1.170213 (2925 3775);
PAINT GREEN (2925 3775);
DISPLAY INVISIBLE (2925 3775);
FORCEPROP 1 LAST COMMENT_BODY TRUE
J 0
(2550 3800);
DISPLAY 1.170213 (2550 3800);
PAINT GREEN (2550 3800);
DISPLAY INVISIBLE (2550 3800);
FORCEPROP 2 LAST PATH I44
J 0
(2800 3975);
DISPLAY 1.021277 (2800 3975);
DISPLAY INVISIBLE (2800 3975);
FORCEADD OFFPAGE..3
(3400 4500);
FORCEPROP 2 LAST $XR2 274 
J 0
(3824 4500);
DISPLAY 0.638298 (3824 4500);
PAINT MONO (3824 4500);
FORCEPROP 2 LAST $XR1 266 
J 0
(3704 4500);
DISPLAY 0.638298 (3704 4500);
PAINT MONO (3704 4500);
FORCEPROP 2 LAST $XR0 14 
J 0
(3614 4500);
DISPLAY 0.638298 (3614 4500);
PAINT MONO (3614 4500);
FORCEPROP 2 LAST CDS_LIB standard
J 0
(3400 4500);
PAINT MONO (3400 4500);
DISPLAY INVISIBLE (3400 4500);
FORCEPROP 1 LAST OFFPAGE TRUE
J 0
(3725 4375);
DISPLAY 1.170213 (3725 4375);
PAINT GREEN (3725 4375);
DISPLAY INVISIBLE (3725 4375);
FORCEPROP 1 LAST COMMENT_BODY TRUE
J 0
(3350 4400);
DISPLAY 1.170213 (3350 4400);
PAINT GREEN (3350 4400);
DISPLAY INVISIBLE (3350 4400);
FORCEPROP 2 LAST PATH I46
J 0
(3600 4575);
DISPLAY 1.021277 (3600 4575);
DISPLAY INVISIBLE (3600 4575);
FORCEADD OFFPAGE..1
(-2675 4200);
FORCEPROP 2 LAST $XR0 127 
J 0
(-2957 4200);
DISPLAY 0.638298 (-2957 4200);
PAINT MONO (-2957 4200);
FORCEPROP 2 LAST CDS_LIB standard
J 0
(-2675 4200);
PAINT MONO (-2675 4200);
DISPLAY INVISIBLE (-2675 4200);
FORCEPROP 1 LAST OFFPAGE TRUE
J 0
(-2350 4075);
DISPLAY 0.872340 (-2350 4075);
DISPLAY INVISIBLE (-2350 4075);
FORCEPROP 1 LAST COMMENT_BODY TRUE
J 0
(-2550 4100);
DISPLAY 0.872340 (-2550 4100);
PAINT GREEN (-2550 4100);
DISPLAY INVISIBLE (-2550 4100);
FORCEPROP 2 LAST PATH I5
J 0
(-2625 4275);
DISPLAY 1.021277 (-2625 4275);
DISPLAY INVISIBLE (-2625 4275);
FORCEADD OFFPAGE..4
(3400 4400);
FORCEPROP 2 LAST $XR2 274 
J 0
(3796 4400);
DISPLAY 0.638298 (3796 4400);
PAINT MONO (3796 4400);
FORCEPROP 2 LAST $XR1 266 
J 0
(3676 4400);
DISPLAY 0.638298 (3676 4400);
PAINT MONO (3676 4400);
FORCEPROP 2 LAST $XR0 14 
J 0
(3586 4400);
DISPLAY 0.638298 (3586 4400);
PAINT MONO (3586 4400);
FORCEPROP 2 LAST CDS_LIB standard
J 0
(3400 4400);
PAINT MONO (3400 4400);
DISPLAY INVISIBLE (3400 4400);
FORCEPROP 1 LAST OFFPAGE TRUE
J 0
(3725 4275);
DISPLAY 1.170213 (3725 4275);
PAINT GREEN (3725 4275);
DISPLAY INVISIBLE (3725 4275);
FORCEPROP 1 LAST COMMENT_BODY TRUE
J 0
(3375 4300);
DISPLAY 1.170213 (3375 4300);
PAINT GREEN (3375 4300);
DISPLAY INVISIBLE (3375 4300);
FORCEPROP 2 LAST PATH I51
J 0
(3575 4475);
DISPLAY 1.021277 (3575 4475);
DISPLAY INVISIBLE (3575 4475);
FORCEADD OFFPAGE..2
(3400 4450);
FORCEPROP 2 LAST $XR1 274 
J 0
(3709 4450);
DISPLAY 0.638298 (3709 4450);
PAINT MONO (3709 4450);
FORCEPROP 2 LAST $XR0 266 
J 0
(3589 4450);
DISPLAY 0.638298 (3589 4450);
PAINT MONO (3589 4450);
FORCEPROP 2 LAST CDS_LIB standard
J 0
(3400 4450);
PAINT MONO (3400 4450);
DISPLAY INVISIBLE (3400 4450);
FORCEPROP 1 LAST OFFPAGE TRUE
J 0
(3725 4325);
DISPLAY 1.170213 (3725 4325);
PAINT GREEN (3725 4325);
DISPLAY INVISIBLE (3725 4325);
FORCEPROP 1 LAST COMMENT_BODY TRUE
J 0
(3355 4355);
DISPLAY 1.170213 (3355 4355);
PAINT GREEN (3355 4355);
DISPLAY INVISIBLE (3355 4355);
FORCEPROP 2 LAST PATH I52
J 0
(3575 4525);
DISPLAY 1.021277 (3575 4525);
DISPLAY INVISIBLE (3575 4525);
FORCEADD OFFPAGE..3
(3400 4300);
FORCEPROP 2 LAST $XR1 278 
J 0
(3704 4300);
DISPLAY 0.638298 (3704 4300);
PAINT MONO (3704 4300);
FORCEPROP 2 LAST $XR0 14 
J 0
(3614 4300);
DISPLAY 0.638298 (3614 4300);
PAINT MONO (3614 4300);
FORCEPROP 2 LAST CDS_LIB standard
J 0
(3400 4300);
PAINT MONO (3400 4300);
DISPLAY INVISIBLE (3400 4300);
FORCEPROP 1 LAST OFFPAGE TRUE
J 0
(3725 4175);
DISPLAY 1.170213 (3725 4175);
PAINT GREEN (3725 4175);
DISPLAY INVISIBLE (3725 4175);
FORCEPROP 1 LAST COMMENT_BODY TRUE
J 0
(3350 4200);
DISPLAY 1.170213 (3350 4200);
PAINT GREEN (3350 4200);
DISPLAY INVISIBLE (3350 4200);
FORCEPROP 2 LAST PATH I53
J 0
(3600 4375);
DISPLAY 1.021277 (3600 4375);
DISPLAY INVISIBLE (3600 4375);
FORCEADD OFFPAGE..2
(3400 4250);
FORCEPROP 2 LAST $XR0 278 
J 0
(3589 4250);
DISPLAY 0.638298 (3589 4250);
PAINT MONO (3589 4250);
FORCEPROP 2 LAST CDS_LIB standard
J 0
(3400 4250);
PAINT MONO (3400 4250);
DISPLAY INVISIBLE (3400 4250);
FORCEPROP 1 LAST OFFPAGE TRUE
J 0
(3725 4125);
DISPLAY 1.170213 (3725 4125);
PAINT GREEN (3725 4125);
DISPLAY INVISIBLE (3725 4125);
FORCEPROP 1 LAST COMMENT_BODY TRUE
J 0
(3355 4155);
DISPLAY 1.170213 (3355 4155);
PAINT GREEN (3355 4155);
DISPLAY INVISIBLE (3355 4155);
FORCEPROP 2 LAST PATH I54
J 0
(3575 4325);
DISPLAY 1.021277 (3575 4325);
DISPLAY INVISIBLE (3575 4325);
FORCEADD OFFPAGE..4
(3400 4200);
FORCEPROP 2 LAST $XR1 278 
J 0
(3676 4200);
DISPLAY 0.638298 (3676 4200);
PAINT MONO (3676 4200);
FORCEPROP 2 LAST $XR0 14 
J 0
(3586 4200);
DISPLAY 0.638298 (3586 4200);
PAINT MONO (3586 4200);
FORCEPROP 2 LAST CDS_LIB standard
J 0
(3400 4200);
PAINT MONO (3400 4200);
DISPLAY INVISIBLE (3400 4200);
FORCEPROP 1 LAST OFFPAGE TRUE
J 0
(3725 4075);
DISPLAY 1.170213 (3725 4075);
PAINT GREEN (3725 4075);
DISPLAY INVISIBLE (3725 4075);
FORCEPROP 1 LAST COMMENT_BODY TRUE
J 0
(3375 4100);
DISPLAY 1.170213 (3375 4100);
PAINT GREEN (3375 4100);
DISPLAY INVISIBLE (3375 4100);
FORCEPROP 2 LAST PATH I55
J 0
(3575 4275);
DISPLAY 1.021277 (3575 4275);
DISPLAY INVISIBLE (3575 4275);
FORCEADD Q_RES..1
(2000 4500);
FORCEPROP 1 LAST PART_NUMBER CS00002JB13
J 0
(2125 4550);
DISPLAY 0.404255 (2125 4550);
DISPLAY INVISIBLE (2125 4550);
FORCEPROP 1 LAST WATTAGE 1/16W
J 2
(2325 4575);
DISPLAY 0.404255 (2325 4575);
FORCEPROP 1 LAST MATERIAL CHIP
J 0
(2125 4575);
DISPLAY 0.404255 (2125 4575);
FORCEPROP 1 LAST VALUE 0
J 2
(2150 4500);
DISPLAY 0.404255 (2150 4500);
FORCEPROP 1 LAST TOLERANCE 5%
J 0
(2175 4500);
DISPLAY 0.404255 (2175 4500);
FORCEPROP 1 LAST PACK_TYPE 0402LF
J 0
(2250 4500);
DISPLAY 0.404255 (2250 4500);
FORCEPROP 1 LAST $LOCATION R12
J 0
(1825 4500);
DISPLAY 0.510638 (1825 4500);
FORCEPROP 1 LASTPIN (1900 4500) $PN 1
J 0
(1912 4512);
DISPLAY 0.787234 (1912 4512);
FORCEPROP 1 LASTPIN (2100 4500) $PN 2
J 0
(2062 4512);
DISPLAY 0.787234 (2062 4512);
FORCEPROP 2 LAST CDS_LIB pure_quanta
J 0
(2000 4500);
PAINT MONO (2000 4500);
DISPLAY INVISIBLE (2000 4500);
FORCEPROP 1 LAST $LOCATION R12
J 0
(1950 4700);
DISPLAY 1.021277 (1950 4700);
DISPLAY INVISIBLE (1950 4700);
FORCEPROP 2 LAST CDS_LOCATION R12
J 0
(1950 4700);
DISPLAY 1.021277 (1950 4700);
DISPLAY INVISIBLE (1950 4700);
FORCEPROP 2 LAST $SEC 1
J 0
(1950 4700);
DISPLAY 0.680851 (1950 4700);
PAINT MONO (1950 4700);
DISPLAY INVISIBLE (1950 4700);
FORCEPROP 2 LAST CDS_SEC 1
J 0
(1950 4700);
DISPLAY 1.021277 (1950 4700);
DISPLAY INVISIBLE (1950 4700);
FORCEPROP 1 LAST PATH I59
J 0
(1950 4650);
DISPLAY 0.978723 (1950 4650);
PAINT WHITE (1950 4650);
DISPLAY INVISIBLE (1950 4650);
FORCEADD OFFPAGE..1
(-2675 4150);
FORCEPROP 2 LAST $XR0 127 
J 0
(-2957 4150);
DISPLAY 0.638298 (-2957 4150);
PAINT MONO (-2957 4150);
FORCEPROP 2 LAST CDS_LIB standard
J 0
(-2675 4150);
PAINT MONO (-2675 4150);
DISPLAY INVISIBLE (-2675 4150);
FORCEPROP 1 LAST OFFPAGE TRUE
J 0
(-2350 4025);
DISPLAY 0.872340 (-2350 4025);
DISPLAY INVISIBLE (-2350 4025);
FORCEPROP 1 LAST COMMENT_BODY TRUE
J 0
(-2550 4050);
DISPLAY 0.872340 (-2550 4050);
PAINT GREEN (-2550 4050);
DISPLAY INVISIBLE (-2550 4050);
FORCEPROP 2 LAST PATH I6
J 0
(-2625 4225);
DISPLAY 1.021277 (-2625 4225);
DISPLAY INVISIBLE (-2625 4225);
FORCEADD Q_RES..1
(2000 4450);
FORCEPROP 1 LAST PART_NUMBER CS00002JB13
J 0
(2125 4425);
DISPLAY 0.404255 (2125 4425);
DISPLAY INVISIBLE (2125 4425);
FORCEPROP 1 LAST VALUE 0
J 2
(2150 4450);
DISPLAY 0.404255 (2150 4450);
FORCEPROP 1 LAST TOLERANCE 5%
J 0
(2175 4450);
DISPLAY 0.404255 (2175 4450);
FORCEPROP 1 LAST PACK_TYPE 0402LF
J 0
(2250 4450);
DISPLAY 0.404255 (2250 4450);
FORCEPROP 1 LAST $LOCATION R13
J 0
(1825 4450);
DISPLAY 0.510638 (1825 4450);
FORCEPROP 1 LASTPIN (1900 4450) $PN 1
J 0
(1912 4462);
DISPLAY 0.787234 (1912 4462);
FORCEPROP 1 LASTPIN (2100 4450) $PN 2
J 0
(2062 4462);
DISPLAY 0.787234 (2062 4462);
FORCEPROP 2 LAST CDS_LIB pure_quanta
J 0
(2000 4450);
PAINT MONO (2000 4450);
DISPLAY INVISIBLE (2000 4450);
FORCEPROP 1 LAST WATTAGE 1/16W
J 2
(2450 4425);
DISPLAY 0.404255 (2450 4425);
DISPLAY INVISIBLE (2450 4425);
FORCEPROP 1 LAST MATERIAL CHIP
J 0
(2475 4425);
DISPLAY 0.404255 (2475 4425);
DISPLAY INVISIBLE (2475 4425);
FORCEPROP 1 LAST $LOCATION R13
J 0
(1950 4650);
DISPLAY 1.021277 (1950 4650);
DISPLAY INVISIBLE (1950 4650);
FORCEPROP 2 LAST CDS_LOCATION R13
J 0
(1950 4650);
DISPLAY 1.021277 (1950 4650);
DISPLAY INVISIBLE (1950 4650);
FORCEPROP 2 LAST $SEC 1
J 0
(1950 4650);
DISPLAY 0.680851 (1950 4650);
PAINT MONO (1950 4650);
DISPLAY INVISIBLE (1950 4650);
FORCEPROP 2 LAST CDS_SEC 1
J 0
(1950 4650);
DISPLAY 1.021277 (1950 4650);
DISPLAY INVISIBLE (1950 4650);
FORCEPROP 1 LAST PATH I60
J 0
(1950 4600);
DISPLAY 0.978723 (1950 4600);
PAINT WHITE (1950 4600);
DISPLAY INVISIBLE (1950 4600);
FORCEADD Q_RES..1
(2000 4400);
FORCEPROP 1 LAST PART_NUMBER CS12002FB06
J 0
(2125 4375);
DISPLAY 0.404255 (2125 4375);
DISPLAY INVISIBLE (2125 4375);
FORCEPROP 1 LAST MATERIAL CHIP
J 0
(2125 4350);
DISPLAY 0.404255 (2125 4350);
FORCEPROP 1 LAST TOLERANCE 1%
J 0
(2175 4400);
DISPLAY 0.404255 (2175 4400);
FORCEPROP 1 LAST VALUE 200
J 2
(2150 4400);
DISPLAY 0.404255 (2150 4400);
FORCEPROP 1 LAST WATTAGE 1/16W
J 2
(2325 4350);
DISPLAY 0.404255 (2325 4350);
FORCEPROP 1 LAST PACK_TYPE 0402LF
J 0
(2250 4400);
DISPLAY 0.404255 (2250 4400);
FORCEPROP 1 LAST $LOCATION R14
J 0
(1825 4400);
DISPLAY 0.510638 (1825 4400);
FORCEPROP 2 LAST CDS_LIB pure_quanta
J 0
(2000 4400);
PAINT MONO (2000 4400);
DISPLAY INVISIBLE (2000 4400);
FORCEPROP 2 LAST CDS_LOCATION R14
J 0
(1950 4600);
DISPLAY 1.021277 (1950 4600);
DISPLAY INVISIBLE (1950 4600);
FORCEPROP 2 LAST $SEC 1
J 0
(1950 4600);
DISPLAY 0.680851 (1950 4600);
PAINT MONO (1950 4600);
DISPLAY INVISIBLE (1950 4600);
FORCEPROP 2 LAST CDS_SEC 1
J 0
(1950 4600);
DISPLAY 1.021277 (1950 4600);
DISPLAY INVISIBLE (1950 4600);
FORCEPROP 1 LASTPIN (1900 4400) $PN 1
J 0
(1912 4412);
DISPLAY 0.787234 (1912 4412);
DISPLAY INVISIBLE (1912 4412);
FORCEPROP 1 LASTPIN (2100 4400) $PN 2
J 0
(2062 4412);
DISPLAY 0.787234 (2062 4412);
DISPLAY INVISIBLE (2062 4412);
FORCEPROP 1 LAST PATH I61
J 0
(1950 4550);
DISPLAY 0.978723 (1950 4550);
PAINT WHITE (1950 4550);
DISPLAY INVISIBLE (1950 4550);
FORCEADD Q_RES..1
(2000 4300);
FORCEPROP 1 LAST PART_NUMBER CS00002JB13
J 0
(2125 4275);
DISPLAY 0.404255 (2125 4275);
DISPLAY INVISIBLE (2125 4275);
FORCEPROP 1 LAST TOLERANCE 5%
J 0
(2175 4300);
DISPLAY 0.404255 (2175 4300);
FORCEPROP 1 LAST VALUE 0
J 2
(2150 4300);
DISPLAY 0.404255 (2150 4300);
FORCEPROP 1 LAST PACK_TYPE 0402LF
J 0
(2250 4300);
DISPLAY 0.404255 (2250 4300);
FORCEPROP 1 LAST $LOCATION R15
J 0
(1825 4300);
DISPLAY 0.510638 (1825 4300);
FORCEPROP 1 LASTPIN (1900 4300) $PN 1
J 0
(1912 4312);
DISPLAY 0.787234 (1912 4312);
FORCEPROP 1 LASTPIN (2100 4300) $PN 2
J 0
(2062 4312);
DISPLAY 0.787234 (2062 4312);
FORCEPROP 2 LAST CDS_LIB pure_quanta
J 0
(2000 4300);
PAINT MONO (2000 4300);
DISPLAY INVISIBLE (2000 4300);
FORCEPROP 1 LAST WATTAGE 1/16W
J 2
(2450 4275);
DISPLAY 0.404255 (2450 4275);
DISPLAY INVISIBLE (2450 4275);
FORCEPROP 1 LAST MATERIAL CHIP
J 0
(2475 4275);
DISPLAY 0.404255 (2475 4275);
DISPLAY INVISIBLE (2475 4275);
FORCEPROP 1 LAST $LOCATION R15
J 0
(1950 4500);
DISPLAY 1.021277 (1950 4500);
DISPLAY INVISIBLE (1950 4500);
FORCEPROP 2 LAST CDS_LOCATION R15
J 0
(1950 4500);
DISPLAY 1.021277 (1950 4500);
DISPLAY INVISIBLE (1950 4500);
FORCEPROP 2 LAST $SEC 1
J 0
(1950 4500);
DISPLAY 0.680851 (1950 4500);
PAINT MONO (1950 4500);
DISPLAY INVISIBLE (1950 4500);
FORCEPROP 2 LAST CDS_SEC 1
J 0
(1950 4500);
DISPLAY 1.021277 (1950 4500);
DISPLAY INVISIBLE (1950 4500);
FORCEPROP 1 LAST PATH I62
J 0
(1950 4450);
DISPLAY 0.978723 (1950 4450);
PAINT WHITE (1950 4450);
DISPLAY INVISIBLE (1950 4450);
FORCEADD Q_RES..1
(2000 4250);
FORCEPROP 1 LAST PART_NUMBER CS00002JB13
J 0
(2125 4225);
DISPLAY 0.404255 (2125 4225);
DISPLAY INVISIBLE (2125 4225);
FORCEPROP 1 LAST TOLERANCE 5%
J 0
(2175 4250);
DISPLAY 0.404255 (2175 4250);
FORCEPROP 1 LAST PACK_TYPE 0402LF
J 0
(2250 4250);
DISPLAY 0.404255 (2250 4250);
FORCEPROP 1 LAST VALUE 0
J 2
(2150 4250);
DISPLAY 0.404255 (2150 4250);
FORCEPROP 1 LAST $LOCATION R16
J 0
(1825 4250);
DISPLAY 0.510638 (1825 4250);
FORCEPROP 1 LASTPIN (1900 4250) $PN 1
J 0
(1912 4262);
DISPLAY 0.787234 (1912 4262);
FORCEPROP 1 LASTPIN (2100 4250) $PN 2
J 0
(2062 4262);
DISPLAY 0.787234 (2062 4262);
FORCEPROP 2 LAST CDS_LIB pure_quanta
J 0
(2000 4250);
PAINT MONO (2000 4250);
DISPLAY INVISIBLE (2000 4250);
FORCEPROP 1 LAST MATERIAL CHIP
J 0
(2475 4225);
DISPLAY 0.404255 (2475 4225);
DISPLAY INVISIBLE (2475 4225);
FORCEPROP 1 LAST WATTAGE 1/16W
J 2
(2450 4225);
DISPLAY 0.404255 (2450 4225);
DISPLAY INVISIBLE (2450 4225);
FORCEPROP 1 LAST $LOCATION R16
J 0
(1950 4450);
DISPLAY 1.021277 (1950 4450);
DISPLAY INVISIBLE (1950 4450);
FORCEPROP 2 LAST CDS_LOCATION R16
J 0
(1950 4450);
DISPLAY 1.021277 (1950 4450);
DISPLAY INVISIBLE (1950 4450);
FORCEPROP 2 LAST $SEC 1
J 0
(1950 4450);
DISPLAY 0.680851 (1950 4450);
PAINT MONO (1950 4450);
DISPLAY INVISIBLE (1950 4450);
FORCEPROP 2 LAST CDS_SEC 1
J 0
(1950 4450);
DISPLAY 1.021277 (1950 4450);
DISPLAY INVISIBLE (1950 4450);
FORCEPROP 1 LAST PATH I63
J 0
(1950 4400);
DISPLAY 0.978723 (1950 4400);
PAINT WHITE (1950 4400);
DISPLAY INVISIBLE (1950 4400);
FORCEADD Q_RES..1
(2000 4200);
FORCEPROP 1 LAST PART_NUMBER CS12002FB06
J 0
(2125 4175);
DISPLAY 0.404255 (2125 4175);
DISPLAY INVISIBLE (2125 4175);
FORCEPROP 1 LAST MATERIAL CHIP
J 0
(2125 4150);
DISPLAY 0.404255 (2125 4150);
FORCEPROP 1 LAST WATTAGE 1/16W
J 2
(2325 4150);
DISPLAY 0.404255 (2325 4150);
FORCEPROP 1 LAST PACK_TYPE 0402LF
J 0
(2250 4200);
DISPLAY 0.404255 (2250 4200);
FORCEPROP 1 LAST TOLERANCE 1%
J 0
(2175 4200);
DISPLAY 0.404255 (2175 4200);
FORCEPROP 1 LAST VALUE 200
J 2
(2150 4200);
DISPLAY 0.404255 (2150 4200);
FORCEPROP 1 LAST $LOCATION R17
J 0
(1825 4200);
DISPLAY 0.510638 (1825 4200);
FORCEPROP 2 LAST CDS_LIB pure_quanta
J 0
(2000 4200);
PAINT MONO (2000 4200);
DISPLAY INVISIBLE (2000 4200);
FORCEPROP 2 LAST CDS_LOCATION R17
J 0
(1950 4400);
DISPLAY 1.021277 (1950 4400);
DISPLAY INVISIBLE (1950 4400);
FORCEPROP 2 LAST $SEC 1
J 0
(1950 4400);
DISPLAY 0.680851 (1950 4400);
PAINT MONO (1950 4400);
DISPLAY INVISIBLE (1950 4400);
FORCEPROP 2 LAST CDS_SEC 1
J 0
(1950 4400);
DISPLAY 1.021277 (1950 4400);
DISPLAY INVISIBLE (1950 4400);
FORCEPROP 1 LASTPIN (1900 4200) $PN 1
J 0
(1912 4212);
DISPLAY 0.787234 (1912 4212);
DISPLAY INVISIBLE (1912 4212);
FORCEPROP 1 LASTPIN (2100 4200) $PN 2
J 0
(2062 4212);
DISPLAY 0.787234 (2062 4212);
DISPLAY INVISIBLE (2062 4212);
FORCEPROP 1 LAST PATH I64
J 0
(1950 4350);
DISPLAY 0.978723 (1950 4350);
PAINT WHITE (1950 4350);
DISPLAY INVISIBLE (1950 4350);
FORCEADD OFFPAGE..1
(-2850 1200);
FORCEPROP 2 LAST $XR0 14 
J 0
(-3071 1200);
DISPLAY 0.638298 (-3071 1200);
PAINT MONO (-3071 1200);
FORCEPROP 2 LAST CDS_LIB standard
J 0
(-2850 1200);
PAINT MONO (-2850 1200);
DISPLAY INVISIBLE (-2850 1200);
FORCEPROP 1 LAST OFFPAGE TRUE
J 0
(-2525 1075);
DISPLAY 0.872340 (-2525 1075);
DISPLAY INVISIBLE (-2525 1075);
FORCEPROP 1 LAST COMMENT_BODY TRUE
J 0
(-2725 1100);
DISPLAY 0.872340 (-2725 1100);
PAINT GREEN (-2725 1100);
DISPLAY INVISIBLE (-2725 1100);
FORCEPROP 2 LAST PATH I65
J 0
(-2800 1275);
DISPLAY 1.021277 (-2800 1275);
DISPLAY INVISIBLE (-2800 1275);
FORCEADD Q_RES..1
(-1600 1200);
FORCEPROP 1 LAST PART_NUMBER CS03322FB03
J 0
(-1750 1300);
DISPLAY 0.638298 (-1750 1300);
DISPLAY INVISIBLE (-1750 1300);
FORCEPROP 1 LAST VALUE 33.2
J 2
(-1325 1200);
DISPLAY 0.638298 (-1325 1200);
FORCEPROP 1 LAST WATTAGE 1/16W
J 2
(-1350 1350);
DISPLAY 0.638298 (-1350 1350);
FORCEPROP 1 LAST TOLERANCE 1%
J 0
(-1300 1200);
DISPLAY 0.638298 (-1300 1200);
FORCEPROP 1 LAST MATERIAL CHIP
J 0
(-1200 1200);
DISPLAY 0.638298 (-1200 1200);
FORCEPROP 1 LAST PACK_TYPE 0402LF
J 0
(-1750 1350);
DISPLAY 0.638298 (-1750 1350);
FORCEPROP 1 LAST $LOCATION R7
J 0
(-1850 1200);
DISPLAY 0.787234 (-1850 1200);
FORCEPROP 1 LASTPIN (-1700 1200) $PN 1
J 0
(-1688 1212);
DISPLAY 0.787234 (-1688 1212);
FORCEPROP 1 LASTPIN (-1500 1200) $PN 2
J 0
(-1538 1212);
DISPLAY 0.787234 (-1538 1212);
FORCEPROP 2 LAST CDS_LIB pure_quanta
J 0
(-1600 1200);
PAINT MONO (-1600 1200);
DISPLAY INVISIBLE (-1600 1200);
FORCEPROP 1 LAST $LOCATION R7
J 0
(-1300 1425);
DISPLAY 1.021277 (-1300 1425);
DISPLAY INVISIBLE (-1300 1425);
FORCEPROP 2 LAST CDS_LOCATION R7
J 0
(-1300 1425);
DISPLAY 1.021277 (-1300 1425);
DISPLAY INVISIBLE (-1300 1425);
FORCEPROP 2 LAST $SEC 1
J 0
(-1300 1425);
DISPLAY 0.680851 (-1300 1425);
PAINT MONO (-1300 1425);
DISPLAY INVISIBLE (-1300 1425);
FORCEPROP 2 LAST CDS_SEC 1
J 0
(-1300 1425);
DISPLAY 1.021277 (-1300 1425);
DISPLAY INVISIBLE (-1300 1425);
FORCEPROP 1 LAST PATH I66
J 0
(-1650 1350);
DISPLAY 0.978723 (-1650 1350);
PAINT WHITE (-1650 1350);
DISPLAY INVISIBLE (-1650 1350);
FORCEADD OFFPAGE..2
(225 1200);
FORCEPROP 2 LAST $XR0 184 
J 0
(414 1200);
DISPLAY 0.638298 (414 1200);
PAINT MONO (414 1200);
FORCEPROP 2 LAST CDS_LIB standard
J 0
(225 1200);
PAINT MONO (225 1200);
DISPLAY INVISIBLE (225 1200);
FORCEPROP 1 LAST OFFPAGE TRUE
J 0
(550 1075);
DISPLAY 1.170213 (550 1075);
PAINT GREEN (550 1075);
DISPLAY INVISIBLE (550 1075);
FORCEPROP 1 LAST COMMENT_BODY TRUE
J 0
(180 1105);
DISPLAY 1.170213 (180 1105);
PAINT GREEN (180 1105);
DISPLAY INVISIBLE (180 1105);
FORCEPROP 2 LAST PATH I67
J 0
(400 1275);
DISPLAY 1.021277 (400 1275);
DISPLAY INVISIBLE (400 1275);
FORCEADD OFFPAGE..1
(-2675 4100);
FORCEPROP 2 LAST $XR0 127 
J 0
(-2957 4100);
DISPLAY 0.638298 (-2957 4100);
PAINT MONO (-2957 4100);
FORCEPROP 2 LAST CDS_LIB standard
J 0
(-2675 4100);
PAINT MONO (-2675 4100);
DISPLAY INVISIBLE (-2675 4100);
FORCEPROP 1 LAST OFFPAGE TRUE
J 0
(-2350 3975);
DISPLAY 0.872340 (-2350 3975);
DISPLAY INVISIBLE (-2350 3975);
FORCEPROP 1 LAST COMMENT_BODY TRUE
J 0
(-2550 4000);
DISPLAY 0.872340 (-2550 4000);
PAINT GREEN (-2550 4000);
DISPLAY INVISIBLE (-2550 4000);
FORCEPROP 2 LAST PATH I7
J 0
(-2625 4175);
DISPLAY 1.021277 (-2625 4175);
DISPLAY INVISIBLE (-2625 4175);
FORCEADD OFFPAGE..2
(225 500);
FORCEPROP 2 LAST $XR0 14 
J 0
(414 500);
DISPLAY 0.638298 (414 500);
PAINT MONO (414 500);
FORCEPROP 2 LAST CDS_LIB standard
J 0
(225 500);
PAINT MONO (225 500);
DISPLAY INVISIBLE (225 500);
FORCEPROP 1 LAST OFFPAGE TRUE
J 0
(550 375);
DISPLAY 1.170213 (550 375);
PAINT GREEN (550 375);
DISPLAY INVISIBLE (550 375);
FORCEPROP 1 LAST COMMENT_BODY TRUE
J 0
(180 405);
DISPLAY 1.170213 (180 405);
PAINT GREEN (180 405);
DISPLAY INVISIBLE (180 405);
FORCEPROP 2 LAST PATH I76
J 0
(400 575);
DISPLAY 1.021277 (400 575);
DISPLAY INVISIBLE (400 575);
FORCEADD Q_RES..1
(-1600 500);
FORCEPROP 1 LAST PART_NUMBER CS03322FB03
J 0
(-1750 600);
DISPLAY 0.638298 (-1750 600);
DISPLAY INVISIBLE (-1750 600);
FORCEPROP 1 LAST TOLERANCE 1%
J 0
(-1325 500);
DISPLAY 0.638298 (-1325 500);
FORCEPROP 1 LAST MATERIAL CHIP
J 0
(-1225 500);
DISPLAY 0.638298 (-1225 500);
FORCEPROP 1 LAST PACK_TYPE 0402LF
J 0
(-1750 650);
DISPLAY 0.638298 (-1750 650);
FORCEPROP 1 LAST WATTAGE 1/16W
J 2
(-1375 650);
DISPLAY 0.638298 (-1375 650);
FORCEPROP 1 LAST VALUE 33.2
J 2
(-1350 500);
DISPLAY 0.638298 (-1350 500);
FORCEPROP 1 LAST $LOCATION R10
J 0
(-1850 500);
DISPLAY 0.638298 (-1850 500);
FORCEPROP 1 LASTPIN (-1700 500) $PN 1
J 0
(-1688 512);
DISPLAY 0.787234 (-1688 512);
FORCEPROP 1 LASTPIN (-1500 500) $PN 2
J 0
(-1538 512);
DISPLAY 0.787234 (-1538 512);
FORCEPROP 2 LAST CDS_LIB pure_quanta
J 0
(-1600 500);
PAINT MONO (-1600 500);
DISPLAY INVISIBLE (-1600 500);
FORCEPROP 1 LAST $LOCATION R10
J 0
(-1300 725);
DISPLAY 1.021277 (-1300 725);
DISPLAY INVISIBLE (-1300 725);
FORCEPROP 2 LAST CDS_LOCATION R10
J 0
(-1300 725);
DISPLAY 1.021277 (-1300 725);
DISPLAY INVISIBLE (-1300 725);
FORCEPROP 2 LAST $SEC 1
J 0
(-1300 725);
DISPLAY 0.680851 (-1300 725);
PAINT MONO (-1300 725);
DISPLAY INVISIBLE (-1300 725);
FORCEPROP 2 LAST CDS_SEC 1
J 0
(-1300 725);
DISPLAY 1.021277 (-1300 725);
DISPLAY INVISIBLE (-1300 725);
FORCEPROP 1 LAST PATH I78
J 0
(-1650 650);
DISPLAY 0.978723 (-1650 650);
PAINT WHITE (-1650 650);
DISPLAY INVISIBLE (-1650 650);
FORCEADD Q_RES..1
(-1600 -225);
FORCEPROP 1 LAST PART_NUMBER CS03322FB03
J 0
(-1750 -125);
DISPLAY 0.638298 (-1750 -125);
DISPLAY INVISIBLE (-1750 -125);
FORCEPROP 1 LAST WATTAGE 1/16W
J 2
(-1375 -75);
DISPLAY 0.638298 (-1375 -75);
FORCEPROP 1 LAST VALUE 33.2
J 2
(-1350 -225);
DISPLAY 0.638298 (-1350 -225);
FORCEPROP 1 LAST TOLERANCE 1%
J 0
(-1325 -225);
DISPLAY 0.638298 (-1325 -225);
FORCEPROP 1 LAST MATERIAL CHIP
J 0
(-1225 -225);
DISPLAY 0.638298 (-1225 -225);
FORCEPROP 1 LAST PACK_TYPE 0402LF
J 0
(-1750 -75);
DISPLAY 0.638298 (-1750 -75);
FORCEPROP 1 LAST $LOCATION R11
J 0
(-1850 -225);
DISPLAY 0.638298 (-1850 -225);
FORCEPROP 1 LASTPIN (-1700 -225) $PN 1
J 0
(-1688 -213);
DISPLAY 0.787234 (-1688 -213);
FORCEPROP 1 LASTPIN (-1500 -225) $PN 2
J 0
(-1538 -213);
DISPLAY 0.787234 (-1538 -213);
FORCEPROP 2 LAST CDS_LIB pure_quanta
J 0
(-1600 -225);
PAINT MONO (-1600 -225);
DISPLAY INVISIBLE (-1600 -225);
FORCEPROP 1 LAST $LOCATION R11
J 0
(-1300 0);
DISPLAY 1.021277 (-1300 0);
DISPLAY INVISIBLE (-1300 0);
FORCEPROP 2 LAST CDS_LOCATION R11
J 0
(-1300 0);
DISPLAY 1.021277 (-1300 0);
DISPLAY INVISIBLE (-1300 0);
FORCEPROP 2 LAST $SEC 1
J 0
(-1300 0);
DISPLAY 0.680851 (-1300 0);
PAINT MONO (-1300 0);
DISPLAY INVISIBLE (-1300 0);
FORCEPROP 2 LAST CDS_SEC 1
J 0
(-1300 0);
DISPLAY 1.021277 (-1300 0);
DISPLAY INVISIBLE (-1300 0);
FORCEPROP 1 LAST PATH I79
J 0
(-1650 -75);
DISPLAY 0.978723 (-1650 -75);
PAINT WHITE (-1650 -75);
DISPLAY INVISIBLE (-1650 -75);
FORCEADD OFFPAGE..1
(-2675 4050);
FORCEPROP 2 LAST $XR0 127 
J 0
(-2957 4050);
DISPLAY 0.638298 (-2957 4050);
PAINT MONO (-2957 4050);
FORCEPROP 2 LAST CDS_LIB standard
J 0
(-2675 4050);
PAINT MONO (-2675 4050);
DISPLAY INVISIBLE (-2675 4050);
FORCEPROP 1 LAST OFFPAGE TRUE
J 0
(-2350 3925);
DISPLAY 0.872340 (-2350 3925);
DISPLAY INVISIBLE (-2350 3925);
FORCEPROP 1 LAST COMMENT_BODY TRUE
J 0
(-2550 3950);
DISPLAY 0.872340 (-2550 3950);
PAINT GREEN (-2550 3950);
DISPLAY INVISIBLE (-2550 3950);
FORCEPROP 2 LAST PATH I8
J 0
(-2625 4125);
DISPLAY 1.021277 (-2625 4125);
DISPLAY INVISIBLE (-2625 4125);
FORCEADD OFFPAGE..1
(-2850 500);
FORCEPROP 2 LAST $XR0 14 
J 0
(-3071 500);
DISPLAY 0.638298 (-3071 500);
PAINT MONO (-3071 500);
FORCEPROP 2 LAST CDS_LIB standard
J 0
(-2850 500);
PAINT MONO (-2850 500);
DISPLAY INVISIBLE (-2850 500);
FORCEPROP 1 LAST OFFPAGE TRUE
J 0
(-2525 375);
DISPLAY 0.872340 (-2525 375);
DISPLAY INVISIBLE (-2525 375);
FORCEPROP 1 LAST COMMENT_BODY TRUE
J 0
(-2725 400);
DISPLAY 0.872340 (-2725 400);
PAINT GREEN (-2725 400);
DISPLAY INVISIBLE (-2725 400);
FORCEPROP 2 LAST PATH I80
J 0
(-2800 575);
DISPLAY 1.021277 (-2800 575);
DISPLAY INVISIBLE (-2800 575);
FORCEADD OFFPAGE..3
R 2
(-2675 3900);
FORCEPROP 2 LAST $XR0 235 
J 0
(-2985 3900);
DISPLAY 0.638298 (-2985 3900);
PAINT MONO (-2985 3900);
FORCEPROP 2 LAST CDS_LIB standard
J 0
(-2675 3900);
DISPLAY INVISIBLE (-2675 3900);
FORCEPROP 1 LAST OFFPAGE TRUE
J 2
(-3000 3775);
DISPLAY 0.872340 (-3000 3775);
DISPLAY INVISIBLE (-3000 3775);
FORCEPROP 1 LAST COMMENT_BODY TRUE
J 2
(-2625 3800);
DISPLAY 0.872340 (-2625 3800);
PAINT GREEN (-2625 3800);
DISPLAY INVISIBLE (-2625 3800);
FORCEPROP 2 LAST PATH I9
J 0
(-2625 3975);
DISPLAY 1.021277 (-2625 3975);
DISPLAY INVISIBLE (-2625 3975);
FORCEADD Q_RES..1
(-1600 -475);
FORCEPROP 1 LAST PART_NUMBER CS03322FB03
J 0
(-1750 -375);
DISPLAY 0.638298 (-1750 -375);
DISPLAY INVISIBLE (-1750 -375);
FORCEPROP 1 LAST WATTAGE 1/16W
J 2
(-1400 -325);
DISPLAY 0.638298 (-1400 -325);
FORCEPROP 1 LAST VALUE 33.2
J 2
(-1350 -475);
DISPLAY 0.638298 (-1350 -475);
FORCEPROP 1 LAST TOLERANCE 1%
J 0
(-1325 -475);
DISPLAY 0.638298 (-1325 -475);
FORCEPROP 1 LAST MATERIAL CHIP
J 0
(-1225 -475);
DISPLAY 0.638298 (-1225 -475);
FORCEPROP 1 LAST PACK_TYPE 0402LF
J 0
(-1750 -325);
DISPLAY 0.638298 (-1750 -325);
FORCEPROP 1 LAST $LOCATION R322
J 0
(-1850 -475);
DISPLAY 0.638298 (-1850 -475);
FORCEPROP 1 LASTPIN (-1700 -475) $PN 1
J 0
(-1688 -463);
DISPLAY 0.787234 (-1688 -463);
FORCEPROP 1 LASTPIN (-1500 -475) $PN 2
J 0
(-1538 -463);
DISPLAY 0.787234 (-1538 -463);
FORCEPROP 2 LAST CDS_LIB pure_quanta
J 0
(-1600 -475);
PAINT MONO (-1600 -475);
DISPLAY INVISIBLE (-1600 -475);
FORCEPROP 2 LAST CDS_LOCATION R322
J 0
(-1400 -275);
DISPLAY 1.021277 (-1400 -275);
DISPLAY INVISIBLE (-1400 -275);
FORCEPROP 2 LAST $SEC 1
J 0
(-1400 -275);
DISPLAY 0.680851 (-1400 -275);
PAINT MONO (-1400 -275);
DISPLAY INVISIBLE (-1400 -275);
FORCEPROP 2 LAST CDS_SEC 1
J 0
(-1400 -275);
DISPLAY 1.021277 (-1400 -275);
DISPLAY INVISIBLE (-1400 -275);
FORCEPROP 1 LAST PATH I90
J 0
(-1650 -325);
DISPLAY 0.978723 (-1650 -325);
PAINT WHITE (-1650 -325);
DISPLAY INVISIBLE (-1650 -325);
FORCEADD OFFPAGE..4
(225 -475);
FORCEPROP 2 LAST $XR0 14 
J 0
(411 -475);
DISPLAY 0.638298 (411 -475);
PAINT MONO (411 -475);
FORCEPROP 2 LAST CDS_LIB standard
J 0
(225 -475);
PAINT MONO (225 -475);
DISPLAY INVISIBLE (225 -475);
FORCEPROP 1 LAST OFFPAGE TRUE
J 0
(550 -600);
DISPLAY 1.170213 (550 -600);
PAINT GREEN (550 -600);
DISPLAY INVISIBLE (550 -600);
FORCEPROP 1 LAST COMMENT_BODY TRUE
J 0
(200 -575);
DISPLAY 1.170213 (200 -575);
PAINT GREEN (200 -575);
DISPLAY INVISIBLE (200 -575);
FORCEPROP 2 LAST PATH I91
J 0
(425 -425);
DISPLAY 1.021277 (425 -425);
DISPLAY INVISIBLE (425 -425);
FORCEADD OFFPAGE..2
R 2
(-2850 -475);
FORCEPROP 2 LAST $XR0 14 
J 0
(-3074 -475);
DISPLAY 0.638298 (-3074 -475);
PAINT MONO (-3074 -475);
FORCEPROP 2 LAST CDS_LIB standard
J 0
(-2850 -475);
PAINT MONO (-2850 -475);
DISPLAY INVISIBLE (-2850 -475);
FORCEPROP 1 LAST OFFPAGE TRUE
J 2
(-3175 -600);
DISPLAY 0.872340 (-3175 -600);
DISPLAY INVISIBLE (-3175 -600);
FORCEPROP 1 LAST COMMENT_BODY TRUE
J 2
(-2805 -570);
DISPLAY 0.872340 (-2805 -570);
PAINT GREEN (-2805 -570);
DISPLAY INVISIBLE (-2805 -570);
FORCEPROP 2 LAST PATH I92
J 0
(-3100 -425);
DISPLAY 1.021277 (-3100 -425);
DISPLAY INVISIBLE (-3100 -425);
FORCEADD Q_RES..1
(2975 375);
FORCEPROP 1 LAST PART_NUMBER CS11002FB07
J 0
(2800 425);
DISPLAY 0.510638 (2800 425);
DISPLAY INVISIBLE (2800 425);
FORCEPROP 1 LAST PACK_TYPE 0402LF
J 0
(2800 475);
DISPLAY 0.510638 (2800 475);
FORCEPROP 1 LAST VALUE 100
J 2
(3175 375);
DISPLAY 0.638298 (3175 375);
FORCEPROP 1 LAST TOLERANCE 1%
J 0
(3225 375);
DISPLAY 0.638298 (3225 375);
FORCEPROP 1 LAST WATTAGE 1/16W
J 2
(3125 475);
DISPLAY 0.510638 (3125 475);
FORCEPROP 1 LAST MATERIAL CHIP
J 0
(3300 375);
DISPLAY 0.638298 (3300 375);
FORCEPROP 1 LAST $LOCATION R328
J 0
(2725 375);
DISPLAY 0.808511 (2725 375);
FORCEPROP 1 LASTPIN (2875 375) $PN 1
J 0
(2887 387);
DISPLAY 0.787234 (2887 387);
FORCEPROP 1 LASTPIN (3075 375) $PN 2
J 0
(3037 387);
DISPLAY 0.787234 (3037 387);
FORCEPROP 2 LAST CDS_LIB pure_quanta
J 0
(2975 375);
PAINT MONO (2975 375);
DISPLAY INVISIBLE (2975 375);
FORCEPROP 2 LAST CDS_LOCATION R328
J 0
(2925 575);
DISPLAY 1.021277 (2925 575);
DISPLAY INVISIBLE (2925 575);
FORCEPROP 2 LAST $SEC 1
J 0
(2925 575);
DISPLAY 0.680851 (2925 575);
PAINT MONO (2925 575);
DISPLAY INVISIBLE (2925 575);
FORCEPROP 2 LAST CDS_SEC 1
J 0
(2925 575);
DISPLAY 1.021277 (2925 575);
DISPLAY INVISIBLE (2925 575);
FORCEPROP 1 LAST PATH I93
J 0
(2925 525);
DISPLAY 0.978723 (2925 525);
PAINT WHITE (2925 525);
DISPLAY INVISIBLE (2925 525);
FORCEADD Q_RES..1
(2975 175);
FORCEPROP 1 LAST PART_NUMBER CS04992FB07
J 0
(2825 225);
DISPLAY 0.638298 (2825 225);
DISPLAY INVISIBLE (2825 225);
FORCEPROP 1 LAST TOLERANCE 1%
J 0
(3225 175);
DISPLAY 0.638298 (3225 175);
FORCEPROP 1 LAST MATERIAL CHIP
J 0
(3300 175);
DISPLAY 0.638298 (3300 175);
FORCEPROP 1 LAST PACK_TYPE 0402LF
J 0
(2825 275);
DISPLAY 0.638298 (2825 275);
FORCEPROP 1 LAST WATTAGE 1/16W
J 2
(3175 275);
DISPLAY 0.638298 (3175 275);
FORCEPROP 1 LAST VALUE 49.9
J 2
(3225 175);
DISPLAY 0.638298 (3225 175);
FORCEPROP 1 LAST $LOCATION R548
J 0
(2725 175);
DISPLAY 0.808511 (2725 175);
FORCEPROP 1 LASTPIN (2875 175) $PN 1
J 0
(2887 187);
DISPLAY 0.787234 (2887 187);
FORCEPROP 1 LASTPIN (3075 175) $PN 2
J 0
(3037 187);
DISPLAY 0.787234 (3037 187);
FORCEPROP 2 LAST CDS_LIB pure_quanta
J 0
(2975 175);
PAINT MONO (2975 175);
DISPLAY INVISIBLE (2975 175);
FORCEPROP 2 LAST CDS_LOCATION R548
J 0
(2925 375);
DISPLAY 1.021277 (2925 375);
DISPLAY INVISIBLE (2925 375);
FORCEPROP 2 LAST $SEC 1
J 0
(2925 375);
DISPLAY 0.680851 (2925 375);
PAINT MONO (2925 375);
DISPLAY INVISIBLE (2925 375);
FORCEPROP 2 LAST CDS_SEC 1
J 0
(2925 375);
DISPLAY 1.021277 (2925 375);
DISPLAY INVISIBLE (2925 375);
FORCEPROP 1 LAST PATH I94
J 0
(2925 325);
DISPLAY 0.978723 (2925 325);
PAINT WHITE (2925 325);
DISPLAY INVISIBLE (2925 325);
FORCEADD UNIVERSAL_POWER..1
(3525 600);
FORCEPROP 3 LASTPIN (3525 550) SIG_NAME PVNN_TERM_CPU0\g
J 0
(3535 560);
DISPLAY 0.659574 (3535 560);
PAINT MONO (3535 560);
DISPLAY INVISIBLE (3535 560);
FORCEPROP 1 LAST HDL_POWER PVNN_TERM_CPU0
J 1
(3525 650);
DISPLAY 0.872340 (3525 650);
PAINT GREEN (3525 650);
FORCEPROP 2 LAST CDS_LIB logical_power
J 0
(3525 600);
PAINT MONO (3525 600);
DISPLAY INVISIBLE (3525 600);
FORCEPROP 1 LAST PATH I95
J 0
(3575 625);
DISPLAY 0.872340 (3575 625);
PAINT AQUA (3575 625);
DISPLAY INVISIBLE (3575 625);
FORCEADD OFFPAGE..2
R 2
(1650 375);
FORCEPROP 2 LAST $XR2 274 
J 0
(1186 375);
DISPLAY 0.638298 (1186 375);
PAINT MONO (1186 375);
FORCEPROP 2 LAST $XR1 266 
J 0
(1306 375);
DISPLAY 0.638298 (1306 375);
PAINT MONO (1306 375);
FORCEPROP 2 LAST $XR0 14 
J 0
(1426 375);
DISPLAY 0.638298 (1426 375);
PAINT MONO (1426 375);
FORCEPROP 2 LAST CDS_LIB standard
J 0
(1650 375);
PAINT MONO (1650 375);
DISPLAY INVISIBLE (1650 375);
FORCEPROP 1 LAST OFFPAGE TRUE
J 2
(1325 250);
DISPLAY 0.872340 (1325 250);
DISPLAY INVISIBLE (1325 250);
FORCEPROP 1 LAST COMMENT_BODY TRUE
J 2
(1695 280);
DISPLAY 0.872340 (1695 280);
PAINT GREEN (1695 280);
DISPLAY INVISIBLE (1695 280);
FORCEPROP 2 LAST PATH I96
J 0
(1400 425);
DISPLAY 1.021277 (1400 425);
DISPLAY INVISIBLE (1400 425);
FORCEADD OFFPAGE..2
R 2
(1650 175);
FORCEPROP 2 LAST $XR2 14 
J 0
(1185 175);
DISPLAY 0.638298 (1185 175);
PAINT MONO (1185 175);
FORCEPROP 2 LAST $XR1 274 
J 0
(1275 175);
DISPLAY 0.638298 (1275 175);
PAINT MONO (1275 175);
FORCEPROP 2 LAST $XR0 266 
J 0
(1395 175);
DISPLAY 0.638298 (1395 175);
PAINT MONO (1395 175);
FORCEPROP 2 LAST CDS_LIB standard
J 0
(1650 175);
PAINT MONO (1650 175);
DISPLAY INVISIBLE (1650 175);
FORCEPROP 1 LAST OFFPAGE TRUE
J 2
(1325 50);
DISPLAY 0.872340 (1325 50);
DISPLAY INVISIBLE (1325 50);
FORCEPROP 1 LAST COMMENT_BODY TRUE
J 2
(1695 80);
DISPLAY 0.872340 (1695 80);
PAINT GREEN (1695 80);
DISPLAY INVISIBLE (1695 80);
FORCEPROP 2 LAST PATH I97
J 0
(1400 225);
DISPLAY 1.021277 (1400 225);
DISPLAY INVISIBLE (1400 225);
FORCEADD Q_RES..1
(2975 -25);
FORCEPROP 1 LAST PART_NUMBER CS11002FB07
J 0
(2800 25);
DISPLAY 0.510638 (2800 25);
DISPLAY INVISIBLE (2800 25);
FORCEPROP 1 LAST MATERIAL CHIP
J 0
(3300 -25);
DISPLAY 0.638298 (3300 -25);
FORCEPROP 1 LAST VALUE 100
J 2
(3175 -25);
DISPLAY 0.638298 (3175 -25);
FORCEPROP 1 LAST PACK_TYPE 0402LF
J 0
(2800 75);
DISPLAY 0.510638 (2800 75);
FORCEPROP 1 LAST TOLERANCE 1%
J 0
(3225 -25);
DISPLAY 0.638298 (3225 -25);
FORCEPROP 1 LAST WATTAGE 1/16W
J 2
(3125 75);
DISPLAY 0.510638 (3125 75);
FORCEPROP 1 LAST $LOCATION R555
J 0
(2725 -25);
DISPLAY 0.808511 (2725 -25);
FORCEPROP 1 LASTPIN (2875 -25) $PN 1
J 0
(2887 -13);
DISPLAY 0.787234 (2887 -13);
FORCEPROP 1 LASTPIN (3075 -25) $PN 2
J 0
(3037 -13);
DISPLAY 0.787234 (3037 -13);
FORCEPROP 2 LAST CDS_LIB pure_quanta
J 0
(2975 -25);
PAINT MONO (2975 -25);
DISPLAY INVISIBLE (2975 -25);
FORCEPROP 2 LAST CDS_LOCATION R555
J 0
(2925 175);
DISPLAY 1.021277 (2925 175);
DISPLAY INVISIBLE (2925 175);
FORCEPROP 2 LAST $SEC 1
J 0
(2925 175);
DISPLAY 0.680851 (2925 175);
PAINT MONO (2925 175);
DISPLAY INVISIBLE (2925 175);
FORCEPROP 2 LAST CDS_SEC 1
J 0
(2925 175);
DISPLAY 1.021277 (2925 175);
DISPLAY INVISIBLE (2925 175);
FORCEPROP 1 LAST PATH I98
J 0
(2925 125);
DISPLAY 0.978723 (2925 125);
PAINT WHITE (2925 125);
DISPLAY INVISIBLE (2925 125);
FORCEADD OFFPAGE..2
R 2
(1650 -25);
FORCEPROP 2 LAST $XR1 278 
J 0
(1306 -25);
DISPLAY 0.638298 (1306 -25);
PAINT MONO (1306 -25);
FORCEPROP 2 LAST $XR0 14 
J 0
(1426 -25);
DISPLAY 0.638298 (1426 -25);
PAINT MONO (1426 -25);
FORCEPROP 2 LAST CDS_LIB standard
J 0
(1650 -25);
PAINT MONO (1650 -25);
DISPLAY INVISIBLE (1650 -25);
FORCEPROP 1 LAST OFFPAGE TRUE
J 2
(1325 -150);
DISPLAY 0.872340 (1325 -150);
DISPLAY INVISIBLE (1325 -150);
FORCEPROP 1 LAST COMMENT_BODY TRUE
J 2
(1695 -120);
DISPLAY 0.872340 (1695 -120);
PAINT GREEN (1695 -120);
DISPLAY INVISIBLE (1695 -120);
FORCEPROP 2 LAST PATH I99
J 0
(1400 25);
DISPLAY 1.021277 (1400 25);
DISPLAY INVISIBLE (1400 25);
FORCEADD CAD_NOTE..1
(-4375 1500);
FORCEPROP 0 LAST S2 PLACE R7 CLOSE TO PCH
J 0
(-4525 1275);
DISPLAY 0.808511 (-4525 1275);
PAINT SKYBLUE (-4525 1275);
FORCEPROP 0 LAST S1 PLACE R1959 CLOSE TO CPU0
J 0
(-4525 1350);
DISPLAY 0.808511 (-4525 1350);
PAINT SKYBLUE (-4525 1350);
FORCEPROP 2 LAST CDS_LIB logical_power
J 0
(-4375 1500);
DISPLAY INVISIBLE (-4375 1500);
FORCEPROP 1 LAST COMMENT_BODY TRUE
J 0
(-4350 1600);
DISPLAY 0.978723 (-4350 1600);
DISPLAY INVISIBLE (-4350 1600);
FORCEADD CAD_NOTE..1
(-4375 800);
FORCEPROP 0 LAST S1 PLACE R1960 CLOSE TO PCH
J 0
(-4525 650);
DISPLAY 0.808511 (-4525 650);
PAINT SKYBLUE (-4525 650);
FORCEPROP 0 LAST S2 PLACE R10 CLOSE TO CPU0
J 0
(-4525 575);
DISPLAY 0.808511 (-4525 575);
PAINT SKYBLUE (-4525 575);
FORCEPROP 2 LAST CDS_LIB logical_power
J 0
(-4375 800);
DISPLAY INVISIBLE (-4375 800);
FORCEPROP 1 LAST COMMENT_BODY TRUE
J 0
(-4350 900);
DISPLAY 0.978723 (-4350 900);
DISPLAY INVISIBLE (-4350 900);
FORCEADD CAD_NOTE..1
(-4375 75);
FORCEPROP 0 LAST S3 PLACE R2362 CLOSE TO CPU0
J 0
(-4525 -75);
DISPLAY 0.808511 (-4525 -75);
PAINT SKYBLUE (-4525 -75);
FORCEPROP 0 LAST S1 PLACE R11 CLOSE TO CPU1
J 0
(-4525 -150);
DISPLAY 0.808511 (-4525 -150);
PAINT SKYBLUE (-4525 -150);
FORCEPROP 0 LAST S2 PLACE R322 CLOSE TO CPU0
J 0
(-4525 -225);
DISPLAY 0.808511 (-4525 -225);
PAINT SKYBLUE (-4525 -225);
FORCEPROP 0 LAST S4 PLACE R4089 CLOSE TO CPU1
J 0
(-4525 -300);
DISPLAY 0.808511 (-4525 -300);
PAINT SKYBLUE (-4525 -300);
FORCEPROP 2 LAST CDS_LIB logical_power
J 0
(-4375 75);
DISPLAY INVISIBLE (-4375 75);
FORCEPROP 1 LAST COMMENT_BODY TRUE
J 0
(-4350 175);
DISPLAY 0.978723 (-4350 175);
DISPLAY INVISIBLE (-4350 175);
FORCEADD QUANTA_TITLE_BLOCK_C..1
(4350 -1075);
FORCEPROP 0 LAST CDS_CON_LAST_MODIFIED Fri Aug 25 14:00:00 2023
J 0
(2465 -1060);
PAINT MONO (2465 -1060);
DISPLAY INVISIBLE (2465 -1060);
FORCEPROP 2 LAST CUSTOM_TXT_CDS <XR_PAGE_TITLE>
J 0
(-3540 4175);
DISPLAY 0.638298 (-3540 4175);
PAINT PINK (-3540 4175);
DISPLAY INVISIBLE (-3540 4175);
FORCEPROP 2 LAST CUSTOM_TXT_CDS <CON_LAST_MODIFIED>
J 0
(2465 -1060);
DISPLAY 0.978723 (2465 -1060);
FORCEPROP 2 LAST CUSTOM_TXT_CDS <Q_NUMBER>
J 0
(2947 -972);
DISPLAY 1.212766 (2947 -972);
FORCEPROP 2 LAST CUSTOM_TXT_CDS <Q_PROJ>
J 0
(1968 -973);
DISPLAY 1.212766 (1968 -973);
FORCEPROP 2 LAST CUSTOM_TXT_CDS <Q_REV>
J 0
(4166 -972);
DISPLAY 1.212766 (4166 -972);
FORCEPROP 2 LAST CUSTOM_TXT_CDS <CON_PAGE_NUM> OF <CON_TOTAL_PAGES>
J 0
(3904 -1057);
DISPLAY 0.978723 (3904 -1057);
FORCEPROP 1 LAST CUSTOM_TXT_CDS <NAME_2>
J 0
(1175 -1025);
FORCEPROP 1 LAST CUSTOM_TXT_CDS <NAME_1>
J 0
(1175 -900);
FORCEPROP 1 LAST Q_TITLE SPR CPU0 MISC:SMBUS/SVID/ERRORS(2/30)
J 0
(-5016 -1049);
DISPLAY 1.957447 (-5016 -1049);
PAINT GREEN (-5016 -1049);
FORCEPROP 1 LAST Q_DEPT 
J 1
(587 -1026);
DISPLAY 1.957447 (587 -1026);
PAINT GREEN (587 -1026);
FORCEPROP 2 LAST PAGE_BORDER TRUE
J 0
(-3540 4175);
DISPLAY 0.638298 (-3540 4175);
PAINT PINK (-3540 4175);
DISPLAY INVISIBLE (-3540 4175);
FORCEPROP 1 LAST CDS_LMAN_SYM_OUTLINE -9475,6775,100,-125
J 0
(4350 -1075);
DISPLAY 0.468085 (4350 -1075);
PAINT GREEN (4350 -1075);
DISPLAY INVISIBLE (4350 -1075);
FORCEPROP 2 LAST CDS_LIB pure_quanta
J 0
(4350 -1075);
PAINT MONO (4350 -1075);
DISPLAY INVISIBLE (4350 -1075);
FORCEPROP 2 LAST CDS_XR_PAGE_TITLE CR-14 : @S9S_MB_2U_LIB.S9S_MB_2U(SCH_1):PAGE14
J 0
(-3540 4175);
DISPLAY 0.638298 (-3540 4175);
PAINT PINK (-3540 4175);
DISPLAY INVISIBLE (-3540 4175);
FORCEPROP 1 LAST COMMENT_BODY TRUE
J 0
(4362 -1088);
DISPLAY 0.978723 (4362 -1088);
PAINT GREEN (4362 -1088);
DISPLAY INVISIBLE (4362 -1088);
WIRE 16 -1 (3525 550)(3525 375);
WIRE 16 -1 (3525 -225)(3075 -225);
WIRE 16 -1 (3525 -25)(3075 -25);
WIRE 16 -1 (3525 -25)(3525 -225);
WIRE 16 -1 (3525 175)(3525 -25);
WIRE 16 -1 (3525 175)(3075 175);
WIRE 16 -1 (3525 375)(3075 375);
WIRE 16 -1 (3525 375)(3525 175);
WIRE 16 -1 (2875 -225)(1700 -225);
FORCEPROP 0 LAST CDS_PHYS_NET_NAME SVID_DIO0_CPU0_R
J 0
(2234 -184);
PAINT MONO (2234 -184);
DISPLAY INVISIBLE (2234 -184);
FORCEPROP 2 LAST SIG_NAME SVID_ALERT1_CPU0_R_N
J 0
(1809 -216);
DISPLAY 0.680851 (1809 -216);
PAINT WHITE (1809 -216);
WIRE 16 -1 (2875 -25)(1700 -25);
FORCEPROP 0 LAST CDS_PHYS_NET_NAME SVID_DIO0_CPU0_R
J 0
(2234 16);
PAINT MONO (2234 16);
DISPLAY INVISIBLE (2234 16);
FORCEPROP 2 LAST SIG_NAME SVID_DIO1_CPU0_R
J 0
(1809 -16);
DISPLAY 0.680851 (1809 -16);
PAINT WHITE (1809 -16);
WIRE 16 -1 (2875 175)(1700 175);
FORCEPROP 0 LAST CDS_PHYS_NET_NAME SVID_ALERT0_CPU0_R_N
J 0
(2234 216);
PAINT MONO (2234 216);
DISPLAY INVISIBLE (2234 216);
FORCEPROP 2 LAST SIG_NAME SVID_ALERT0_CPU0_R_N
J 0
(1809 184);
DISPLAY 0.680851 (1809 184);
PAINT WHITE (1809 184);
FORCEPROP 0 LAST $PHYS_NET_NAME SVID_ALERT0_CPU0_R_N
J 0
(2234 263);
PAINT MONO (2234 263);
DISPLAY INVISIBLE (2234 263);
WIRE 16 -1 (3350 4500)(2100 4500);
FORCEPROP 2 LAST SIG_NAME SVID_DIO0_CPU0_R
J 0
(2634 4509);
DISPLAY 0.680851 (2634 4509);
PAINT WHITE (2634 4509);
WIRE 16 -1 (2875 375)(1700 375);
FORCEPROP 0 LAST CDS_PHYS_NET_NAME SVID_DIO0_CPU0_R
J 0
(2234 416);
PAINT MONO (2234 416);
DISPLAY INVISIBLE (2234 416);
FORCEPROP 2 LAST SIG_NAME SVID_DIO0_CPU0_R
J 0
(1809 384);
DISPLAY 0.680851 (1809 384);
PAINT WHITE (1809 384);
WIRE 16 -1 (-1575 3950)(-2625 3950);
FORCEPROP 2 LAST SIG_NAME SMB_PEHPCPU0_GTL_SCL
J 0
(-2562 3959);
DISPLAY 0.553191 (-2562 3959);
PAINT WHITE (-2562 3959);
WIRE 16 -1 (-1575 3900)(-2625 3900);
FORCEPROP 2 LAST SIG_NAME SMB_PEHPCPU0_GTL_SDA
J 0
(-2562 3909);
DISPLAY 0.553191 (-2562 3909);
PAINT WHITE (-2562 3909);
WIRE 16 -1 (-1575 3850)(-2625 3850);
FORCEPROP 2 LAST SIG_NAME FM_PEHPCPU0_ALERT_N
J 0
(-2562 3859);
DISPLAY 0.553191 (-2562 3859);
PAINT WHITE (-2562 3859);
WIRE 16 -1 (-1575 2300)(-2625 2300);
FORCEPROP 2 LAST SIG_NAME PWRGD_DRAMPWRGD_CPU0_AB_LVC1_R
J 0
(-2562 2309);
DISPLAY 0.553191 (-2562 2309);
PAINT WHITE (-2562 2309);
WIRE 16 -1 (-1575 2250)(-2625 2250);
FORCEPROP 2 LAST SIG_NAME PWRGD_DRAMPWRGD_CPU0_CD_LVC1_R
J 0
(-2562 2259);
DISPLAY 0.553191 (-2562 2259);
PAINT WHITE (-2562 2259);
WIRE 16 -1 (-1575 2200)(-2625 2200);
FORCEPROP 2 LAST SIG_NAME PWRGD_DRAMPWRGD_CPU0_EF_LVC1_R
J 0
(-2562 2209);
DISPLAY 0.553191 (-2562 2209);
PAINT WHITE (-2562 2209);
WIRE 16 -1 (-1575 2150)(-2625 2150);
FORCEPROP 2 LAST SIG_NAME PWRGD_DRAMPWRGD_CPU0_GH_LVC1_R
J 0
(-2562 2159);
DISPLAY 0.553191 (-2562 2159);
PAINT WHITE (-2562 2159);
WIRE 16 -1 (-1575 3750)(-2625 3750);
FORCEPROP 2 LAST SIG_NAME PD_CPU0_ENH_MCECC_DIS
J 0
(-2562 3759);
DISPLAY 0.553191 (-2562 3759);
PAINT WHITE (-2562 3759);
WIRE 16 -1 (-1575 4050)(-2625 4050);
FORCEPROP 2 LAST SIG_NAME PD_PIROM_CPU0_ADDR2
J 0
(-2562 4059);
DISPLAY 0.553191 (-2562 4059);
PAINT WHITE (-2562 4059);
WIRE 16 -1 (-1575 4100)(-2625 4100);
FORCEPROP 2 LAST SIG_NAME PD_PIROM_CPU0_ADDR1
J 0
(-2562 4109);
DISPLAY 0.553191 (-2562 4109);
PAINT WHITE (-2562 4109);
WIRE 16 -1 (-1575 4150)(-2625 4150);
FORCEPROP 2 LAST SIG_NAME PD_PIROM_CPU0_ADDR0
J 0
(-2562 4159);
DISPLAY 0.553191 (-2562 4159);
PAINT WHITE (-2562 4159);
WIRE 16 -1 (-1575 4300)(-2975 4300);
FORCEPROP 2 LAST SIG_NAME SMB_S3M_CPU0_PIROM_3V3AUX_SCL_R1
J 0
(-2560 4310);
DISPLAY 0.553191 (-2560 4310);
PAINT WHITE (-2560 4310);
WIRE 16 -1 (-1575 4250)(-2975 4250);
FORCEPROP 2 LAST SIG_NAME SMB_S3M_CPU0_PIROM_3V3AUX_SDA_R1
J 0
(-2560 4260);
DISPLAY 0.553191 (-2560 4260);
PAINT WHITE (-2560 4260);
WIRE 16 -1 (-1575 4200)(-2625 4200);
FORCEPROP 2 LAST SIG_NAME PU_PIROM_CPU0_SM_WP
J 0
(-2562 4209);
DISPLAY 0.553191 (-2562 4209);
PAINT WHITE (-2562 4209);
WIRE 16 -1 (-1575 2550)(-2625 2550);
FORCEPROP 2 LAST SIG_NAME TP_H_SBLINK7_CPU0_PMDOWN
J 0
(-2562 2559);
DISPLAY 0.553191 (-2562 2559);
PAINT WHITE (-2562 2559);
WIRE 16 -1 (-1575 2650)(-2625 2650);
FORCEPROP 2 LAST SIG_NAME TP_H_SBLINK6_CPU0_PMDOWN
J 0
(-2562 2659);
DISPLAY 0.553191 (-2562 2659);
PAINT WHITE (-2562 2659);
WIRE 16 -1 (-1575 2750)(-2625 2750);
FORCEPROP 2 LAST SIG_NAME TP_H_SBLINK5_CPU0_PMDOWN
J 0
(-2562 2759);
DISPLAY 0.553191 (-2562 2759);
PAINT WHITE (-2562 2759);
WIRE 16 -1 (-1575 2850)(-2625 2850);
FORCEPROP 2 LAST SIG_NAME TP_H_SBLINK4_CPU0_PMDOWN
J 0
(-2562 2859);
DISPLAY 0.553191 (-2562 2859);
PAINT WHITE (-2562 2859);
WIRE 16 -1 (-1575 2950)(-2625 2950);
FORCEPROP 2 LAST SIG_NAME TP_H_SBLINK3_CPU0_PMDOWN
J 0
(-2562 2959);
DISPLAY 0.553191 (-2562 2959);
PAINT WHITE (-2562 2959);
WIRE 16 -1 (-1575 3050)(-2625 3050);
FORCEPROP 2 LAST SIG_NAME TP_H_SBLINK2_CPU0_PMDOWN
J 0
(-2562 3059);
DISPLAY 0.553191 (-2562 3059);
PAINT WHITE (-2562 3059);
WIRE 16 -1 (-1575 3150)(-2625 3150);
FORCEPROP 2 LAST SIG_NAME H_CPU0_PMDOWN_CPU1_R
J 0
(-2562 3159);
DISPLAY 0.553191 (-2562 3159);
PAINT WHITE (-2562 3159);
WIRE 16 -1 (-1575 3250)(-2625 3250);
FORCEPROP 2 LAST SIG_NAME H_CPU0_PMDOWN_PCH_R2
J 0
(-2562 3259);
DISPLAY 0.553191 (-2562 3259);
PAINT WHITE (-2562 3259);
WIRE 16 -1 (-1575 2600)(-2625 2600);
FORCEPROP 2 LAST SIG_NAME TP_H_SBLINK7_CPU0_PMSYNC
J 0
(-2562 2609);
DISPLAY 0.553191 (-2562 2609);
PAINT WHITE (-2562 2609);
WIRE 16 -1 (-1575 2700)(-2625 2700);
FORCEPROP 2 LAST SIG_NAME TP_H_SBLINK6_CPU0_PMSYNC
J 0
(-2562 2709);
DISPLAY 0.553191 (-2562 2709);
PAINT WHITE (-2562 2709);
WIRE 16 -1 (-1575 2800)(-2625 2800);
FORCEPROP 2 LAST SIG_NAME TP_H_SBLINK5_CPU0_PMSYNC
J 0
(-2562 2809);
DISPLAY 0.553191 (-2562 2809);
PAINT WHITE (-2562 2809);
WIRE 16 -1 (-1575 2900)(-2625 2900);
FORCEPROP 2 LAST SIG_NAME TP_H_SBLINK4_CPU0_PMSYNC
J 0
(-2562 2909);
DISPLAY 0.553191 (-2562 2909);
PAINT WHITE (-2562 2909);
WIRE 16 -1 (-1575 3000)(-2625 3000);
FORCEPROP 2 LAST SIG_NAME TP_H_SBLINK3_CPU0_PMSYNC
J 0
(-2562 3009);
DISPLAY 0.553191 (-2562 3009);
PAINT WHITE (-2562 3009);
WIRE 16 -1 (-1575 3100)(-2625 3100);
FORCEPROP 2 LAST SIG_NAME TP_H_SBLINK2_CPU0_PMSYNC
J 0
(-2562 3109);
DISPLAY 0.553191 (-2562 3109);
PAINT WHITE (-2562 3109);
WIRE 16 -1 (-1575 3200)(-2625 3200);
FORCEPROP 2 LAST SIG_NAME H_CPU0_PMSYNC_CPU1_R
J 0
(-2562 3209);
DISPLAY 0.553191 (-2562 3209);
PAINT WHITE (-2562 3209);
WIRE 16 -1 (-1575 3300)(-2625 3300);
FORCEPROP 2 LAST SIG_NAME H_CPU0_PMSYNC_PCH
J 0
(-2562 3309);
DISPLAY 0.553191 (-2562 3309);
PAINT WHITE (-2562 3309);
WIRE 16 -1 (-1575 2100)(-2625 2100);
FORCEPROP 2 LAST SIG_NAME PWRGD_CPU0_LVC1
J 0
(-2562 2109);
DISPLAY 0.553191 (-2562 2109);
PAINT WHITE (-2562 2109);
WIRE 16 -1 (-1575 2000)(-2625 2000);
FORCEPROP 2 LAST SIG_NAME RST_CPU0_LVC1_N
J 0
(-2562 2009);
DISPLAY 0.553191 (-2562 2009);
PAINT WHITE (-2562 2009);
WIRE 16 -1 (-1575 3350)(-2625 3350);
FORCEPROP 2 LAST SIG_NAME TP_IBL_PLT_RST_SYNC_N
J 0
(-2562 3359);
DISPLAY 0.553191 (-2562 3359);
PAINT WHITE (-2562 3359);
WIRE 16 -1 (-1575 3650)(-2625 3650);
FORCEPROP 2 LAST SIG_NAME FM_CPU0_SKTOCC_LVT3_N
J 0
(-2562 3659);
DISPLAY 0.553191 (-2562 3659);
PAINT WHITE (-2562 3659);
WIRE 16 -1 (-1575 3600)(-2625 3600);
FORCEPROP 2 LAST SIG_NAME PU_TAP_ODT_CPU0_EN
J 0
(-2562 3609);
DISPLAY 0.553191 (-2562 3609);
PAINT WHITE (-2562 3609);
WIRE 16 -1 (2550 3650)(875 3650);
FORCEPROP 2 LAST SIG_NAME H_CPU0_THERMTRIP_LVC1_R_N
J 0
(1109 3659);
DISPLAY 0.680851 (1109 3659);
PAINT WHITE (1109 3659);
WIRE 16 -1 (2550 3400)(875 3400);
FORCEPROP 2 LAST SIG_NAME TP_EV_CPU0_EXT_BGREF
J 0
(1109 3409);
DISPLAY 0.680851 (1109 3409);
PAINT WHITE (1109 3409);
WIRE 16 -1 (1900 4300)(875 4300);
FORCEPROP 2 LAST SIG_NAME SVID_DIO1_CPU0
J 0
(1109 4309);
DISPLAY 0.680851 (1109 4309);
PAINT WHITE (1109 4309);
WIRE 16 -1 (1900 4500)(875 4500);
FORCEPROP 2 LAST SIG_NAME SVID_DIO0_CPU0
J 0
(1109 4509);
DISPLAY 0.680851 (1109 4509);
PAINT WHITE (1109 4509);
WIRE 16 -1 (1900 4250)(875 4250);
FORCEPROP 2 LAST SIG_NAME SVID_CLK1_CPU0
J 0
(1109 4259);
DISPLAY 0.680851 (1109 4259);
PAINT WHITE (1109 4259);
WIRE 16 -1 (1900 4450)(875 4450);
FORCEPROP 2 LAST SIG_NAME SVID_CLK0_CPU0
J 0
(1109 4459);
DISPLAY 0.680851 (1109 4459);
PAINT WHITE (1109 4459);
WIRE 16 -1 (1900 4200)(875 4200);
FORCEPROP 2 LAST SIG_NAME SVID_ALERT1_CPU0_N
J 0
(1109 4209);
DISPLAY 0.680851 (1109 4209);
PAINT WHITE (1109 4209);
WIRE 16 -1 (1900 4400)(875 4400);
FORCEPROP 2 LAST SIG_NAME SVID_ALERT0_CPU0_N
J 0
(1109 4409);
DISPLAY 0.680851 (1109 4409);
PAINT WHITE (1109 4409);
WIRE 16 -1 (2550 2300)(875 2300);
FORCEPROP 2 LAST SIG_NAME NC_CPU0_VIEWPIN_DIE11<0>
J 0
(1109 2309);
DISPLAY 0.680851 (1109 2309);
PAINT WHITE (1109 2309);
WIRE 16 -1 (2550 2800)(875 2800);
FORCEPROP 2 LAST SIG_NAME NC_CPU0_VIEWPIN_DIE01<0>
J 0
(1109 2809);
DISPLAY 0.680851 (1109 2809);
PAINT WHITE (1109 2809);
WIRE 16 -1 (2550 2750)(875 2750);
FORCEPROP 2 LAST SIG_NAME NC_CPU0_VIEWPIN_DIE01<1>
J 0
(1109 2759);
DISPLAY 0.680851 (1109 2759);
PAINT WHITE (1109 2759);
WIRE 16 -1 (2550 2950)(875 2950);
FORCEPROP 2 LAST SIG_NAME NC_CPU0_VIEWPIN_DIE00<2>
J 0
(1109 2959);
DISPLAY 0.680851 (1109 2959);
PAINT WHITE (1109 2959);
WIRE 16 -1 (2550 2650)(875 2650);
FORCEPROP 2 LAST SIG_NAME NC_CPU0_VIEWPIN_DIE01<3>
J 0
(1109 2659);
DISPLAY 0.680851 (1109 2659);
PAINT WHITE (1109 2659);
WIRE 16 -1 (2550 3000)(875 3000);
FORCEPROP 2 LAST SIG_NAME NC_CPU0_VIEWPIN_DIE00<1>
J 0
(1109 3009);
DISPLAY 0.680851 (1109 3009);
PAINT WHITE (1109 3009);
WIRE 16 -1 (2550 2700)(875 2700);
FORCEPROP 2 LAST SIG_NAME NC_CPU0_VIEWPIN_DIE01<2>
J 0
(1109 2709);
DISPLAY 0.680851 (1109 2709);
PAINT WHITE (1109 2709);
WIRE 16 -1 (2550 3050)(875 3050);
FORCEPROP 2 LAST SIG_NAME NC_CPU0_VIEWPIN_DIE00<0>
J 0
(1109 3059);
DISPLAY 0.680851 (1109 3059);
PAINT WHITE (1109 3059);
WIRE 16 -1 (2550 2900)(875 2900);
FORCEPROP 2 LAST SIG_NAME NC_CPU0_VIEWPIN_DIE00<3>
J 0
(1109 2909);
DISPLAY 0.680851 (1109 2909);
PAINT WHITE (1109 2909);
WIRE 16 -1 (2550 3200)(875 3200);
FORCEPROP 2 LAST SIG_NAME NC_CPU0_RSVD<144>
J 0
(1109 3209);
DISPLAY 0.680851 (1109 3209);
PAINT WHITE (1109 3209);
WIRE 16 -1 (2550 2500)(875 2500);
FORCEPROP 2 LAST SIG_NAME NC_CPU0_VIEWPIN_DIE10<1>
J 0
(1109 2509);
DISPLAY 0.680851 (1109 2509);
PAINT WHITE (1109 2509);
WIRE 16 -1 (2550 2400)(875 2400);
FORCEPROP 2 LAST SIG_NAME NC_CPU0_VIEWPIN_DIE10<3>
J 0
(1109 2409);
DISPLAY 0.680851 (1109 2409);
PAINT WHITE (1109 2409);
WIRE 16 -1 (2550 2450)(875 2450);
FORCEPROP 2 LAST SIG_NAME NC_CPU0_VIEWPIN_DIE10<2>
J 0
(1109 2459);
DISPLAY 0.680851 (1109 2459);
PAINT WHITE (1109 2459);
WIRE 16 -1 (2550 2550)(875 2550);
FORCEPROP 2 LAST SIG_NAME NC_CPU0_VIEWPIN_DIE10<0>
J 0
(1109 2559);
DISPLAY 0.680851 (1109 2559);
PAINT WHITE (1109 2559);
WIRE 16 -1 (2550 2250)(875 2250);
FORCEPROP 2 LAST SIG_NAME NC_CPU0_VIEWPIN_DIE11<1>
J 0
(1109 2259);
DISPLAY 0.680851 (1109 2259);
PAINT WHITE (1109 2259);
WIRE 16 -1 (2550 2200)(875 2200);
FORCEPROP 2 LAST SIG_NAME NC_CPU0_VIEWPIN_DIE11<2>
J 0
(1109 2209);
DISPLAY 0.680851 (1109 2209);
PAINT WHITE (1109 2209);
WIRE 16 -1 (2550 2150)(875 2150);
FORCEPROP 2 LAST SIG_NAME NC_CPU0_VIEWPIN_DIE11<3>
J 0
(1109 2159);
DISPLAY 0.680851 (1109 2159);
PAINT WHITE (1109 2159);
WIRE 16 -1 (2550 3850)(875 3850);
FORCEPROP 2 LAST SIG_NAME H_CPU0_PROCHOT_LVC1_N
J 0
(1109 3859);
DISPLAY 0.680851 (1109 3859);
PAINT WHITE (1109 3859);
WIRE 16 -1 (2550 3350)(875 3350);
FORCEPROP 2 LAST SIG_NAME H_CPU0_PM_FAST_WAKE_N
J 0
(1109 3359);
DISPLAY 0.680851 (1109 3359);
PAINT WHITE (1109 3359);
WIRE 16 -1 (2550 3600)(875 3600);
FORCEPROP 2 LAST SIG_NAME H_CPU0_NMI_LVC1_N
J 0
(1109 3609);
DISPLAY 0.680851 (1109 3609);
PAINT WHITE (1109 3609);
WIRE 16 -1 (2550 3700)(875 3700);
FORCEPROP 2 LAST SIG_NAME H_CPU0_MEMTRIP_LVC1_R_N
J 0
(1109 3709);
DISPLAY 0.680851 (1109 3709);
PAINT WHITE (1109 3709);
WIRE 16 -1 (2550 3750)(875 3750);
FORCEPROP 2 LAST SIG_NAME H_CPU0_MEMHOT_OUT_LVC1_R_N
J 0
(1109 3759);
DISPLAY 0.680851 (1109 3759);
PAINT WHITE (1109 3759);
WIRE 16 -1 (2550 3800)(875 3800);
FORCEPROP 2 LAST SIG_NAME H_CPU0_MEMHOT_IN_LVC1_N
J 0
(1109 3809);
DISPLAY 0.680851 (1109 3809);
PAINT WHITE (1109 3809);
WIRE 16 -1 (2550 3450)(875 3450);
FORCEPROP 2 LAST SIG_NAME FM_CPU_FBRK_DEBUG_R_N
J 0
(1109 3459);
DISPLAY 0.680851 (1109 3459);
PAINT WHITE (1109 3459);
WIRE 16 -1 (2550 4100)(875 4100);
FORCEPROP 2 LAST SIG_NAME H_CPU0_ERR0_LVC1_R_N
J 0
(1109 4109);
DISPLAY 0.680851 (1109 4109);
PAINT WHITE (1109 4109);
WIRE 16 -1 (2550 4050)(875 4050);
FORCEPROP 2 LAST SIG_NAME H_CPU0_ERR1_LVC1_R_N
J 0
(1109 4059);
DISPLAY 0.680851 (1109 4059);
PAINT WHITE (1109 4059);
WIRE 16 -1 (2550 4000)(875 4000);
FORCEPROP 2 LAST SIG_NAME H_CPU0_ERR2_LVC1_R_N
J 0
(1109 4009);
DISPLAY 0.680851 (1109 4009);
PAINT WHITE (1109 4009);
WIRE 16 -1 (2550 3900)(875 3900);
FORCEPROP 2 LAST SIG_NAME H_CPU0_CATERR_LVC1_R_N
J 0
(1109 3909);
DISPLAY 0.680851 (1109 3909);
PAINT WHITE (1109 3909);
WIRE 16 273 (-3475 -725)(-3250 -725);
WIRE 16 273 (-3475 25)(-3475 -725);
WIRE 16 273 (-3250 25)(-3475 25);
WIRE 16 2175 (-3100 -800)(525 -800);
WIRE 16 2175 (525 -525)(525 -800);
WIRE 16 2175 (-3100 -525)(-3100 -800);
WIRE 16 2175 (-3100 -525)(525 -525);
WIRE 16 -1 (-1700 -475)(-2800 -475);
FORCEPROP 2 LAST SIG_NAME H_CPU0_PMSYNC_CPU1_R
J 0
(-2737 -466);
DISPLAY 0.680851 (-2737 -466);
PAINT WHITE (-2737 -466);
WIRE 16 -1 (-1700 -725)(-2800 -725);
FORCEPROP 2 LAST SIG_NAME H_CPU0_PMSYNC_CPU1_R1
J 0
(-2737 -716);
DISPLAY 0.680851 (-2737 -716);
PAINT WHITE (-2737 -716);
WIRE 16 -1 (175 500)(-1500 500);
FORCEPROP 2 LAST SIG_NAME H_CPU0_PMSYNC_PCH
J 0
(-737 509);
DISPLAY 0.680851 (-737 509);
PAINT WHITE (-737 509);
WIRE 16 -1 (-1700 -225)(-2800 -225);
FORCEPROP 2 LAST SIG_NAME H_CPU0_PMDOWN_CPU1_R1
J 0
(-2737 -216);
DISPLAY 0.680851 (-2737 -216);
PAINT WHITE (-2737 -216);
WIRE 16 -1 (-1500 25)(175 25);
FORCEPROP 2 LAST SIG_NAME H_CPU0_PMDOWN_CPU1_R1
J 0
(-737 34);
DISPLAY 0.680851 (-737 34);
PAINT WHITE (-737 34);
WIRE 16 -1 (-1500 -225)(175 -225);
FORCEPROP 2 LAST SIG_NAME H_CPU0_PMDOWN_CPU1
J 0
(-737 -216);
DISPLAY 0.680851 (-737 -216);
PAINT WHITE (-737 -216);
WIRE 16 -1 (-1500 -475)(175 -475);
FORCEPROP 2 LAST SIG_NAME H_CPU0_PMSYNC_CPU1_R1
J 0
(-737 -466);
DISPLAY 0.680851 (-737 -466);
PAINT WHITE (-737 -466);
WIRE 16 273 (-3250 1425)(-3475 1425);
WIRE 16 273 (-3475 1425)(-3475 1200);
WIRE 16 273 (-3475 1200)(-3250 1200);
WIRE 16 273 (-3475 525)(-3250 525);
WIRE 16 273 (-3475 750)(-3475 525);
WIRE 16 273 (-3250 750)(-3475 750);
WIRE 16 -1 (-1700 1425)(-2800 1425);
FORCEPROP 2 LAST SIG_NAME H_CPU0_PMDOWN_PCH_R2
J 0
(-2737 1434);
DISPLAY 0.680851 (-2737 1434);
PAINT WHITE (-2737 1434);
WIRE 16 -1 (3350 4450)(2100 4450);
FORCEPROP 2 LAST SIG_NAME SVID_CLK0_CPU0_R
J 0
(2634 4459);
DISPLAY 0.680851 (2634 4459);
PAINT WHITE (2634 4459);
WIRE 16 -1 (3350 4300)(2100 4300);
FORCEPROP 2 LAST SIG_NAME SVID_DIO1_CPU0_R
J 0
(2634 4309);
DISPLAY 0.680851 (2634 4309);
PAINT WHITE (2634 4309);
WIRE 16 -1 (3350 4250)(2100 4250);
FORCEPROP 2 LAST SIG_NAME SVID_CLK1_CPU0_R
J 0
(2634 4259);
DISPLAY 0.680851 (2634 4259);
PAINT WHITE (2634 4259);
WIRE 16 -1 (3350 4400)(2100 4400);
FORCEPROP 2 LAST SIG_NAME SVID_ALERT0_CPU0_R_N
J 0
(2634 4409);
DISPLAY 0.680851 (2634 4409);
PAINT WHITE (2634 4409);
WIRE 16 -1 (3350 4200)(2100 4200);
FORCEPROP 2 LAST SIG_NAME SVID_ALERT1_CPU0_R_N
J 0
(2634 4209);
DISPLAY 0.680851 (2634 4209);
PAINT WHITE (2634 4209);
WIRE 16 -1 (-1700 1200)(-2800 1200);
FORCEPROP 2 LAST SIG_NAME H_CPU0_PMDOWN_PCH_R
J 0
(-2737 1209);
DISPLAY 0.680851 (-2737 1209);
PAINT WHITE (-2737 1209);
WIRE 16 -1 (-1700 750)(-2800 750);
FORCEPROP 2 LAST SIG_NAME H_CPU0_PMSYNC_PCH_R2
J 0
(-2737 759);
DISPLAY 0.680851 (-2737 759);
PAINT WHITE (-2737 759);
WIRE 16 -1 (-1700 500)(-2800 500);
FORCEPROP 2 LAST SIG_NAME H_CPU0_PMSYNC_PCH_R
J 0
(-2737 509);
DISPLAY 0.680851 (-2737 509);
PAINT WHITE (-2737 509);
WIRE 16 -1 (-3175 4250)(-4175 4250);
FORCEPROP 2 LAST SIG_NAME SMB_S3M_CPU0_PIROM_3V3AUX_SDA
J 0
(-4110 4260);
DISPLAY 0.553191 (-4110 4260);
PAINT WHITE (-4110 4260);
WIRE 16 -1 (-3175 4300)(-4175 4300);
FORCEPROP 2 LAST SIG_NAME SMB_S3M_CPU0_PIROM_3V3AUX_SCL
J 0
(-4110 4310);
DISPLAY 0.553191 (-4110 4310);
PAINT WHITE (-4110 4310);
WIRE 16 -1 (175 1425)(-1500 1425);
FORCEPROP 2 LAST SIG_NAME H_CPU0_PMDOWN_PCH_R
J 0
(-737 1434);
DISPLAY 0.680851 (-737 1434);
PAINT WHITE (-737 1434);
WIRE 16 -1 (175 750)(-1500 750);
FORCEPROP 2 LAST SIG_NAME H_CPU0_PMSYNC_PCH_R
J 0
(-737 759);
DISPLAY 0.680851 (-737 759);
PAINT WHITE (-737 759);
WIRE 16 -1 (175 1200)(-1500 1200);
FORCEPROP 2 LAST SIG_NAME H_CPU0_PMDOWN_PCH
J 0
(-737 1209);
DISPLAY 0.680851 (-737 1209);
PAINT WHITE (-737 1209);
WIRE 16 -1 (-1700 25)(-2800 25);
FORCEPROP 2 LAST SIG_NAME H_CPU0_PMDOWN_CPU1_R
J 0
(-2737 34);
DISPLAY 0.680851 (-2737 34);
PAINT WHITE (-2737 34);
WIRE 16 -1 (-1500 -725)(175 -725);
FORCEPROP 2 LAST SIG_NAME H_CPU0_PMSYNC_CPU1
J 0
(-737 -716);
DISPLAY 0.680851 (-737 -716);
PAINT WHITE (-737 -716);
DOT 1 (3525 175);
DOT 1 (3525 -25);
DOT 1 (3525 375);
FORCENOTE
20211129 ADD R4089
(-2150 -900) 0;
DISPLAY LEFT (-2150 -900);
DISPLAY 1.063830 (-2150 -900);
PAINT WHITE (-2150 -900);
FORCENOTE
20210818 MODIFY FOR GT
(-4450 4950) 0;
DISPLAY LEFT (-4450 4950);
DISPLAY 2.510638 (-4450 4950);
PAINT PINK (-4450 4950);
QUIT
